G04 ================== begin FILE IDENTIFICATION RECORD ==================*
G04 Layout Name:  DAT6MTH3AD0_t6m_cm_d_brd_103112_274.brd*
G04 Film Name:    vcc1*
G04 File Format:  Gerber RS274X*
G04 File Origin:  Cadence Allegro 16.3-S048*
G04 Origin Date:  Tue Nov 26 10:18:26 2013*
G04 *
G04 Layer:  VIA CLASS/VCC1*
G04 Layer:  PIN/VCC1*
G04 Layer:  MANUFACTURING/PHOTOPLOT_OUTLINE*
G04 Layer:  ETCH/VCC1*
G04 Layer:  DRAWING FORMAT/TITLE_BLOCK*
G04 Layer:  DRAWING FORMAT/TITLE_DATA_VCC*
G04 *
G04 Offset:    (0.00 0.00)*
G04 Mirror:    No*
G04 Mode:      Negative*
G04 Rotation:  0*
G04 FullContactRelief:  No*
G04 UndefLineWidth:     6.00*
G04 ================== end FILE IDENTIFICATION RECORD ====================*
%FSLAX25Y25*MOIN*%
%IR0*IPPOS*OFA0.00000B0.00000*MIA0B0*SFA1.00000B1.00000*%
%ADD10C,.03*%
%ADD32C,.042*%
%ADD16C,.06*%
%ADD38C,.061*%
%ADD20O,.058X.154*%
%ADD28C,.026*%
%ADD19C,.053*%
%ADD11C,.08*%
%ADD31C,.072*%
%ADD40C,.046*%
%ADD36C,.064*%
%ADD39C,.056*%
%ADD37C,.066*%
%ADD33C,.076*%
%AMMACRO29*
4,1,36,0.0,.004,
.000695,.003939,
.001368,.003759,
.002,.003464,
.002571,.003064,
.003064,.002571,
.003464,.002,
.003759,.001368,
.003939,.000695,
.004,0.0,
.003939,-.000695,
.003759,-.001368,
.003464,-.002,
.003064,-.002571,
.002571,-.003064,
.002,-.003464,
.001368,-.003759,
.000695,-.003939,
0.0,-.004,
-.000695,-.003939,
-.001368,-.003759,
-.002,-.003464,
-.002571,-.003064,
-.003064,-.002571,
-.003464,-.002,
-.003759,-.001368,
-.003939,-.000695,
-.004,0.0,
-.003939,.000695,
-.003759,.001368,
-.003464,.002,
-.003064,.002571,
-.002571,.003064,
-.002,.003464,
-.001368,.003759,
-.000695,.003939,
0.0,.004,
180.*
%
%ADD29MACRO29*%
%AMMACRO24*
4,1,36,0.0,.004,
.000695,.003939,
.001368,.003759,
.002,.003464,
.002571,.003064,
.003064,.002571,
.003464,.002,
.003759,.001368,
.003939,.000695,
.004,0.0,
.003939,-.000695,
.003759,-.001368,
.003464,-.002,
.003064,-.002571,
.002571,-.003064,
.002,-.003464,
.001368,-.003759,
.000695,-.003939,
0.0,-.004,
-.000695,-.003939,
-.001368,-.003759,
-.002,-.003464,
-.002571,-.003064,
-.003064,-.002571,
-.003464,-.002,
-.003759,-.001368,
-.003939,-.000695,
-.004,0.0,
-.003939,.000695,
-.003759,.001368,
-.003464,.002,
-.003064,.002571,
-.002571,.003064,
-.002,.003464,
-.001368,.003759,
-.000695,.003939,
0.0,.004,
270.*
%
%ADD24MACRO24*%
%ADD27C,.095*%
%ADD23C,.068*%
%ADD18C,.077*%
%ADD21C,.089*%
%ADD42C,.11*%
%ADD17C,.15*%
%ADD35C,.233*%
%ADD41C,.18*%
%ADD25C,.172*%
%ADD26C,.148*%
%ADD34C,.188*%
%AMMACRO22*
4,1,36,0.0,.004,
.000695,.003939,
.001368,.003759,
.002,.003464,
.002571,.003064,
.003064,.002571,
.003464,.002,
.003759,.001368,
.003939,.000695,
.004,0.0,
.003939,-.000695,
.003759,-.001368,
.003464,-.002,
.003064,-.002571,
.002571,-.003064,
.002,-.003464,
.001368,-.003759,
.000695,-.003939,
0.0,-.004,
-.000695,-.003939,
-.001368,-.003759,
-.002,-.003464,
-.002571,-.003064,
-.003064,-.002571,
-.003464,-.002,
-.003759,-.001368,
-.003939,-.000695,
-.004,0.0,
-.003939,.000695,
-.003759,.001368,
-.003464,.002,
-.003064,.002571,
-.002571,.003064,
-.002,.003464,
-.001368,.003759,
-.000695,.003939,
0.0,.004,
90.*
%
%ADD22MACRO22*%
%AMMACRO14*
4,1,36,0.0,.004,
.000695,.003939,
.001368,.003759,
.002,.003464,
.002571,.003064,
.003064,.002571,
.003464,.002,
.003759,.001368,
.003939,.000695,
.004,0.0,
.003939,-.000695,
.003759,-.001368,
.003464,-.002,
.003064,-.002571,
.002571,-.003064,
.002,-.003464,
.001368,-.003759,
.000695,-.003939,
0.0,-.004,
-.000695,-.003939,
-.001368,-.003759,
-.002,-.003464,
-.002571,-.003064,
-.003064,-.002571,
-.003464,-.002,
-.003759,-.001368,
-.003939,-.000695,
-.004,0.0,
-.003939,.000695,
-.003759,.001368,
-.003464,.002,
-.003064,.002571,
-.002571,.003064,
-.002,.003464,
-.001368,.003759,
-.000695,.003939,
0.0,.004,
0.0*
%
%ADD14MACRO14*%
%AMMACRO30*
4,1,36,0.0,.004,
.000695,.003939,
.001368,.003759,
.002,.003464,
.002571,.003064,
.003064,.002571,
.003464,.002,
.003759,.001368,
.003939,.000695,
.004,0.0,
.003939,-.000695,
.003759,-.001368,
.003464,-.002,
.003064,-.002571,
.002571,-.003064,
.002,-.003464,
.001368,-.003759,
.000695,-.003939,
0.0,-.004,
-.000695,-.003939,
-.001368,-.003759,
-.002,-.003464,
-.002571,-.003064,
-.003064,-.002571,
-.003464,-.002,
-.003759,-.001368,
-.003939,-.000695,
-.004,0.0,
-.003939,.000695,
-.003759,.001368,
-.003464,.002,
-.003064,.002571,
-.002571,.003064,
-.002,.003464,
-.001368,.003759,
-.000695,.003939,
0.0,.004,
.001*
%
%ADD30MACRO30*%
%ADD43C,.006*%
%ADD50C,.0417*%
%ADD49C,.03154*%
%ADD44C,.07006*%
%ADD46C,.09107*%
%ADD45C,.0971*%
%ADD52C,.07807*%
%ADD51C,.07907*%
%ADD48C,.15206*%
%ADD47C,.15806*%
G75*
%LPD*%
G75*
G36*
G01X-1043962Y-705877D02*
X2300638D01*
Y2342823D01*
X-1043962D01*
Y-705877D01*
G37*
%LPC*%
G75*
G36*
G01X-67803Y813780D02*
G02X-63929Y817654I3874J0D01*
G01X-12373D01*
G02X-11873Y817154I0J-500D01*
G01Y635398D01*
X-11874D01*
Y4500D01*
G02X-12374Y4000I-500J0D01*
G01X-63929D01*
G02X-67803Y7874I0J3874D01*
G01Y813780D01*
G37*
G36*
G01X215198Y272945D02*
G03X217519Y273622I911J1194D01*
G02X217989Y273950I470J-172D01*
G01X226964D01*
G02X227427Y273637I-1J-500D01*
G03X229899Y273151I1394J560D01*
G02X230605Y273162I359J-348D01*
G03X233027Y273648I1043J1081D01*
G02X233486Y273950I459J-198D01*
G01X239492D01*
X239691Y273858D01*
X239763Y273773D01*
G03X242057I1147J969D01*
G02X242439Y273950I382J-323D01*
G01X295108D01*
X295136Y273947D01*
G03X295478I171J1492D01*
G01X295506Y273950D01*
X310276D01*
X314230Y269996D01*
Y259597D01*
X314150Y259473D01*
G03Y257839I1260J-817D01*
G01X314230Y257715D01*
Y220156D01*
X331600Y202786D01*
Y123773D01*
G02X331438Y123404I-500J-1D01*
G03Y121190I1015J-1107D01*
G02X331600Y120821I-338J-368D01*
G01Y56670D01*
G02X331100Y56170I-500J0D01*
G01X260823D01*
X256194Y51541D01*
Y35176D01*
X252921Y31903D01*
Y4500D01*
G02X252421Y4000I-500J0D01*
G01X7874D01*
G02X4000Y7874I0J3874D01*
G01Y115354D01*
G02X5906Y117260I1906J0D01*
G01X25591D01*
G03X35496Y127165I0J9905D01*
G01Y272835D01*
G03X35495Y272939I-9905J-43D01*
G02X36495Y273950I1000J11D01*
G01X173447D01*
X173692Y273793D01*
X173754Y273659D01*
G03X176482I1364J628D01*
G01X176544Y273793D01*
X176789Y273950D01*
X177181D01*
G02X177597Y273727I0J-500D01*
G03X179710Y273375I1221J813D01*
G02X180926I608J-794D01*
G03X183039Y273727I892J1165D01*
G02X183455Y273950I416J-277D01*
G01X200116D01*
X200339Y273829D01*
X200408Y273723D01*
G03X202926I1259J819D01*
G02X203345Y273950I419J-273D01*
G01X211431D01*
X211684Y273778D01*
X211741Y273634D01*
G03X214010Y272964I1397J553D01*
G02X215198Y272945I581J-814D01*
G37*
G36*
G01X124504Y466530D02*
G02X124972Y466207I0J-500D01*
G03X127782I1405J531D01*
G01X127837Y466353D01*
X128093Y466530D01*
X170811D01*
X170920Y466473D01*
G03X170994Y466437I694J1332D01*
G01X171077Y466399D01*
X252251Y385225D01*
X252273Y385057D01*
G03X253564Y383766I1489J198D01*
G01X253732Y383744D01*
X256330Y381146D01*
Y360858D01*
G02X256019Y360395I-500J0D01*
G03Y357615I569J-1390D01*
G01X256161Y357557D01*
X256330Y357305D01*
Y354914D01*
X245301Y343885D01*
Y342865D01*
X245151Y342624D01*
X245023Y342560D01*
G03Y339870I668J-1345D01*
G01X245151Y339806D01*
X245301Y339565D01*
Y337947D01*
X245272Y337865D01*
G03Y336849I1413J-508D01*
G01X245301Y336767D01*
Y301795D01*
X249090Y298006D01*
X249140Y297684D01*
X249065Y297538D01*
G03X251089Y295514I1334J-690D01*
G01X251235Y295589D01*
X251557Y295539D01*
X252968Y294128D01*
X258042D01*
X260360Y291810D01*
Y276450D01*
G02X259860Y275950I-500J0D01*
G01X241814D01*
X241694Y276023D01*
G03X240126I-784J-1281D01*
G01X240006Y275950D01*
X202196D01*
X202122Y275973D01*
G03X201212I-455J-1431D01*
G01X201138Y275950D01*
X182227D01*
X182169Y275964D01*
G03X181467I-351J-1424D01*
G01X181409Y275950D01*
X179227D01*
X179169Y275964D01*
G03X178467I-351J-1424D01*
G01X178409Y275950D01*
X172284D01*
G02X171841Y276218I0J500D01*
G03X169179I-1331J-696D01*
G01X169114Y276094D01*
X168876Y275950D01*
X35347D01*
G02X34879Y276276I1J500D01*
G03X25591Y282740I-9288J-3441D01*
G01X5906D01*
G02X4000Y284646I0J1906D01*
G01Y447530D01*
G02X4500Y448030I500J0D01*
G01X48044D01*
X55430Y455416D01*
Y466030D01*
G02X55930Y466530I500J0D01*
G01X124504D01*
G37*
G36*
G01X49176Y493231D02*
G03X50140Y490386I469J-1427D01*
G02X50659Y490267I165J-472D01*
G01X53430Y487496D01*
Y456244D01*
X47216Y450030D01*
X4500D01*
G02X4000Y450530I0J500D01*
G01Y664173D01*
G02X7874Y668047I3874J0D01*
G01X40787D01*
G03X52661Y679921I0J11874D01*
G01Y817152D01*
G02X53161Y817652I500J0D01*
G01X324476D01*
G02X324976Y817152I0J-500D01*
G01Y792323D01*
G03X340457I7740J0D01*
G01Y817152D01*
G02X340957Y817652I500J0D01*
G01X376051D01*
G02X376551Y817152I0J-500D01*
G01Y793222D01*
X376404Y792982D01*
X376278Y792918D01*
G03X375758Y790680I682J-1338D01*
G02Y789480I-800J-600D01*
G03X376278Y787242I1202J-900D01*
G01X376404Y787178D01*
X376551Y786938D01*
Y741142D01*
G03X410929I17189J0D01*
G01Y817152D01*
G02X411429Y817652I500J0D01*
G01X682744D01*
G02X683244Y817152I0J-500D01*
G01Y793925D01*
G02X682938Y793465I-500J1D01*
G03X683159Y790622I582J-1385D01*
G02X683521Y790269I-120J-485D01*
G03X698724Y792323I7463J2053D01*
G01Y817152D01*
G02X699224Y817652I500J0D01*
G01X734319D01*
G02X734819Y817152I0J-500D01*
G01Y679921D01*
G03X746693Y668047I11874J0D01*
G01X779528D01*
G02X783402Y664173I0J-3874D01*
G01Y297835D01*
G02X781496Y295929I-1906J0D01*
G01X780315D01*
G03X770409Y286024I0J-9906D01*
G01Y132480D01*
G03X780315Y122575I9906J1D01*
G01X781496D01*
G02X783402Y120669I0J-1906D01*
G01Y7874D01*
G02X779528Y4000I-3874J0D01*
G01X291669D01*
G02X291169Y4500I0J500D01*
G01Y31336D01*
X288821Y33684D01*
X276274D01*
X276047Y33911D01*
Y39554D01*
X275949Y39652D01*
X275884Y39930D01*
X275931Y40066D01*
G03X273572Y41726I-1421J487D01*
G02X272948I-312J391D01*
G03X270902Y41567I-938J-1173D01*
G02X270533Y41404I-369J337D01*
G01X270030D01*
G02X269616Y41624I0J500D01*
G03X267434Y41955I-1244J-842D01*
G02X266810I-312J391D01*
G03X264628Y41624I-938J-1173D01*
G02X264214Y41404I-414J280D01*
G01X258694D01*
G02X258194Y41904I0J500D01*
G01Y50713D01*
X261651Y54170D01*
X673374D01*
X689051Y69847D01*
X689253Y69850D01*
G03X699148Y97697I-276J15780D01*
G02X698460Y99177I1246J1479D01*
G01Y105315D01*
G03X698457Y105527I-9483J-28D01*
G01Y106143D01*
X698422Y106178D01*
X698403Y106353D01*
G03X697620Y109216I-9426J-1039D01*
G01Y449031D01*
X702566Y453977D01*
X702766Y453981D01*
G03X704232Y455447I-36J1502D01*
G01X704236Y455647D01*
X716876Y468287D01*
Y515471D01*
G02X717038Y515839I500J0D01*
G03Y518051I-1017J1106D01*
G02X716876Y518419I338J368D01*
G01Y523633D01*
G02X717097Y524048I500J0D01*
G03Y526542I-837J1247D01*
G02X716876Y526957I279J415D01*
G01Y549258D01*
X697620Y568514D01*
Y629314D01*
X661456Y665478D01*
X661388Y665738D01*
X661425Y665870D01*
G03X659574Y667721I-1447J404D01*
G01X659442Y667684D01*
X659182Y667752D01*
X624034Y702900D01*
X569785D01*
X569559Y703026D01*
X569491Y703136D01*
G03X566939I-1276J-793D01*
G01X566871Y703026D01*
X566645Y702900D01*
X489902D01*
X437510Y650508D01*
X437337Y650488D01*
G03X436017Y649168I172J-1492D01*
G01X435997Y648995D01*
X435622Y648620D01*
X435415Y648619D01*
G03X433918Y647122I5J-1502D01*
G01X433917Y646915D01*
X433605Y646603D01*
X433477Y646568D01*
G03X432423Y645514I395J-1449D01*
G01X432388Y645386D01*
X429780Y642778D01*
Y603134D01*
X428856Y602210D01*
X424774D01*
G02X424274Y602710I0J500D01*
G01Y618299D01*
X423642Y618931D01*
X423579Y619216D01*
X423630Y619354D01*
G03X421702Y621282I-1409J519D01*
G01X421564Y621231D01*
X421279Y621294D01*
X411952Y630621D01*
X393437D01*
X388777Y625961D01*
Y602634D01*
X389949Y601462D01*
X397991D01*
X398249Y601204D01*
X398602D01*
X399346Y600460D01*
X402850D01*
G02X403350Y599960I0J-500D01*
G01Y583624D01*
X403176Y583450D01*
X370072D01*
X367950Y585572D01*
Y643797D01*
X367517Y644230D01*
G02X367401Y644756I353J354D01*
G03X365474Y646683I-1411J516D01*
G01X365337Y646632D01*
X365052Y646695D01*
X353206Y658541D01*
X353137Y658798D01*
X353172Y658929D01*
G03X351332Y660769I-1450J390D01*
G02X350848Y660899I-130J483D01*
G01X340331Y671416D01*
X340296Y671482D01*
G03X339676Y672102I-1326J-706D01*
G01X339610Y672137D01*
X337426Y674321D01*
X337355Y674565D01*
X337382Y674690D01*
G03X335594Y676478I-1467J321D01*
G02X335134Y676613I-106J489D01*
G01X308217Y703530D01*
X298200D01*
G02X297865Y703659I0J500D01*
G03X295851I-1007J-1115D01*
G02X295516Y703530I-335J371D01*
G01X295048D01*
X294780Y703735D01*
X294735Y703899D01*
G03X291837I-1449J-395D01*
G02X291354Y703530I-483J131D01*
G01X265853D01*
X265776Y703556D01*
G03X264824I-476J-1425D01*
G01X264747Y703530D01*
X252593D01*
G02X252144Y703810I0J500D01*
G03X249446I-1349J-660D01*
G02X248997Y703530I-449J220D01*
G01X199337D01*
X199072Y703730D01*
X199025Y703891D01*
G03X196139I-1443J-417D01*
G01X196092Y703730D01*
X195827Y703530D01*
X176986D01*
X173760Y700304D01*
Y679024D01*
X49520Y554784D01*
Y552231D01*
G02X49300Y551817I-500J0D01*
G03Y549327I840J-1245D01*
G02X49520Y548913I-280J-414D01*
G01Y530306D01*
X49422Y530174D01*
G03Y528388I1208J-893D01*
G01X49520Y528256D01*
Y522187D01*
X49363Y521942D01*
X49229Y521880D01*
G03Y519152I628J-1364D01*
G01X49363Y519090D01*
X49520Y518845D01*
Y505331D01*
G02X49347Y504953I-500J0D01*
G03Y502681I983J-1136D01*
G01X49430Y502610D01*
X49520Y502413D01*
Y499454D01*
G02X49347Y499076I-500J0D01*
G03Y496804I983J-1136D01*
G01X49430Y496733D01*
X49520Y496536D01*
Y493706D01*
G02X49176Y493231I-500J0D01*
G37*
G36*
G01X324377Y559740D02*
G03X321931I-1223J-873D01*
G02X321524Y559530I-407J290D01*
G01X319174D01*
X318750Y559954D01*
Y573174D01*
X312624Y579300D01*
X224350D01*
X224230Y579372D01*
G03X222676I-777J-1285D01*
G01X222556Y579300D01*
X222056D01*
X217810Y575054D01*
Y566580D01*
X217720Y566450D01*
G03Y564728I1230J-861D01*
G01X217810Y564598D01*
Y544843D01*
X217696Y544704D01*
G03Y542966I1055J-869D01*
G01X217810Y542827D01*
Y527940D01*
G02X217310Y527440I-500J0D01*
G01X107006D01*
X102640Y523074D01*
Y469030D01*
G02X102140Y468530I-500J0D01*
G01X55930D01*
G02X55430Y469030I0J500D01*
G01Y488324D01*
X51520Y492234D01*
Y497012D01*
X51598Y497135D01*
G03Y498745I-1268J805D01*
G01X51520Y498868D01*
Y502889D01*
X51598Y503012D01*
G03Y504622I-1268J805D01*
G01X51520Y504745D01*
Y527840D01*
G02X51673Y528200I500J0D01*
G03Y530362I-1043J1081D01*
G02X51520Y530722I347J360D01*
G01Y549972D01*
X51550Y550056D01*
G03Y551088I-1410J516D01*
G01X51520Y551172D01*
Y553956D01*
X175760Y678196D01*
Y699476D01*
X177018Y700734D01*
X177359Y700776D01*
X177506Y700687D01*
G03X179602Y701266I772J1289D01*
G01X179667Y701388D01*
X179904Y701530D01*
X263628D01*
G02X264046Y701305I0J-500D01*
G03X266554I1254J826D01*
G02X266972Y701530I418J-275D01*
G01X295734D01*
X295875Y701408D01*
G03X297841I983J1136D01*
G01X297982Y701530D01*
X300018D01*
X300265Y701370D01*
X300326Y701235D01*
G03X303066I1370J616D01*
G02X303522Y701530I456J-205D01*
G01X307389D01*
X314695Y694224D01*
X314763Y693959D01*
X314724Y693827D01*
G03X316588Y691963I1441J-423D01*
G02X317082Y691837I141J-480D01*
G01X334560Y674359D01*
X334595Y674295D01*
G03X335199Y673691I1320J716D01*
G01X335263Y673656D01*
X337367Y671552D01*
G02X337502Y671093I-354J-353D01*
G03X339287Y669308I1468J-317D01*
G01X339412Y669335D01*
X339656Y669263D01*
X350613Y658306D01*
X350619Y658299D01*
G03X350702Y658216I1103J1020D01*
G01X350709Y658210D01*
X365950Y642969D01*
Y584744D01*
X369244Y581450D01*
X404004D01*
X405350Y582796D01*
Y599960D01*
G02X405850Y600460I500J0D01*
G01X407466D01*
X407716Y600210D01*
X429684D01*
X431194Y601720D01*
X441196D01*
X444260Y598656D01*
Y526474D01*
X438046Y520260D01*
X388706D01*
X384721Y516275D01*
X384460Y516207D01*
X384329Y516243D01*
G03X383287Y516157I-405J-1446D01*
G01X383186Y516110D01*
X380974D01*
X378036Y519048D01*
G02X377925Y519585I354J353D01*
G03X375975Y521535I-1397J553D01*
G02X375438Y521646I-184J465D01*
G01X367939Y529145D01*
G02X367826Y529679I354J354D01*
G03X365883Y531622I-1400J543D01*
G02X365349Y531735I-180J467D01*
G01X357054Y540030D01*
X335240D01*
G02X334740Y540530I0J500D01*
G01Y557314D01*
X332524Y559530D01*
X324662D01*
X324447Y559641D01*
X324377Y559740D01*
G37*
G36*
G01X446323Y656101D02*
G03X448224Y658002I476J1425D01*
G02X448344Y658514I474J159D01*
G01X468390Y678560D01*
X468697Y678616D01*
X468841Y678550D01*
G03X470832Y680541I626J1365D01*
G02X470933Y681103I455J208D01*
G01X490730Y700900D01*
X567794D01*
X567853Y700885D01*
G03X568577I362J1458D01*
G01X568636Y700900D01*
X623206D01*
X638856Y685250D01*
X638924Y684986D01*
X638887Y684854D01*
G03X640745Y682996I1443J-415D01*
G02X641237Y682869I138J-481D01*
G01X695620Y628486D01*
Y568712D01*
X695521Y568613D01*
Y567785D01*
X695620Y567686D01*
Y567396D01*
X696206Y566810D01*
X696496D01*
X714876Y548430D01*
Y525885D01*
X714847Y525803D01*
G03Y524787I1413J-508D01*
G01X714876Y524705D01*
Y517930D01*
X714787Y517801D01*
G03Y516089I1234J-856D01*
G01X714876Y515960D01*
Y482883D01*
G02X714614Y482443I-500J0D01*
G03Y479801I714J-1321D01*
G02X714876Y479361I-238J-440D01*
G01Y469115D01*
X702756Y456995D01*
X702579Y456977D01*
G03X701236Y455634I151J-1494D01*
G01X701218Y455457D01*
X695620Y449859D01*
Y114149D01*
G02X694082Y113307I-1000J1D01*
G03X679550Y106352I-5106J-7992D01*
G01X679531Y106177D01*
X679497Y106143D01*
Y105566D01*
G03X679494Y105315I9480J-239D01*
G01Y99177D01*
G02X678805Y97697I-1935J0D01*
G03X684706Y70437I10171J-12067D01*
G02X685143Y68767I-270J-963D01*
G01X672546Y56170D01*
X334100D01*
G02X333600Y56670I0J500D01*
G01Y121315D01*
X333689Y121443D01*
G03Y123151I-1236J854D01*
G01X333600Y123279D01*
Y203614D01*
X316230Y220984D01*
Y257151D01*
G02X316400Y257527I500J0D01*
G03Y259785I-990J1129D01*
G02X316230Y260161I330J376D01*
G01Y268910D01*
G02X316730Y269410I500J0D01*
G01X401722D01*
X401922Y269316D01*
X401994Y269230D01*
G03X404302I1154J961D01*
G01X404374Y269316D01*
X404574Y269410D01*
X415204D01*
X417840Y272046D01*
X418095Y272116D01*
X418224Y272083D01*
G03X420052Y273911I373J1455D01*
G01X420019Y274040D01*
X420089Y274295D01*
X482380Y336586D01*
Y421092D01*
X482485Y421228D01*
G03Y423072I-1185J922D01*
G01X482380Y423208D01*
Y454854D01*
X474994Y462240D01*
X390096D01*
X359290Y431434D01*
Y396952D01*
X359180Y396814D01*
G03Y394932I1170J-941D01*
G01X359290Y394794D01*
Y376304D01*
X338486Y355500D01*
X324163D01*
X324022Y355622D01*
G03X322058I-982J-1137D01*
G01X321917Y355500D01*
X320675D01*
X320544Y355594D01*
G03X318788I-878J-1218D01*
G01X318657Y355500D01*
X271190D01*
X270929Y355686D01*
X270877Y355838D01*
G03X268035I-1421J-485D01*
G01X267983Y355686D01*
X267722Y355500D01*
X260346D01*
X260226Y355573D01*
G03X259376Y355791I-782J-1282D01*
G02X258330Y356790I-46J999D01*
G01Y381974D01*
X255340Y384964D01*
X255264Y385149D01*
Y385249D01*
G03X253756Y386757I-1502J6D01*
G02X253401Y386903I-2J500D01*
G01X173229Y467075D01*
G02X173091Y467522I353J354D01*
G03X170429Y468724I-1475J282D01*
G02X170033Y468530I-395J306D01*
G01X137214D01*
G02X136736Y468884I0J500D01*
G03X133864I-1436J-440D01*
G02X133386Y468530I-478J146D01*
G01X105314D01*
X104640Y469204D01*
Y522246D01*
X107834Y525440D01*
X166938D01*
G02X167387Y525159I0J-500D01*
G03X169847I1230J597D01*
G02X170296Y525440I449J-219D01*
G01X217310D01*
G02X217810Y524940I0J-500D01*
G01Y497326D01*
X221666Y493470D01*
X223844D01*
X223896Y493459D01*
G03X224522I313J1469D01*
G01X224574Y493470D01*
X322574D01*
X325300Y496196D01*
Y534716D01*
X326094Y535510D01*
X331634D01*
X334154Y538030D01*
X356226D01*
X380146Y514110D01*
X382432D01*
X382643Y514003D01*
X382714Y513906D01*
G03X385134I1210J891D01*
G01X385283Y514110D01*
X385384D01*
X389534Y518260D01*
X438874D01*
X446260Y525646D01*
Y536449D01*
X446405Y536687D01*
X446530Y536752D01*
G03Y539418I-692J1333D01*
G02X446260Y539862I230J444D01*
G01Y599484D01*
X442024Y603720D01*
X432280D01*
G02X431780Y604220I0J500D01*
G01Y605187D01*
G02X432090Y605649I500J0D01*
G03Y608429I-570J1390D01*
G02X431780Y608891I190J462D01*
G01Y641950D01*
X433311Y643481D01*
G02X433717Y643625I354J-353D01*
G03X435374Y645155I155J1494D01*
G02X435760Y645654I500J12D01*
G03X436910Y646931I-340J1463D01*
G01X436932Y647102D01*
X437322Y647492D01*
X437526Y647494D01*
G03X439011Y648979I-17J1502D01*
G01X439013Y649183D01*
X445811Y655981D01*
G02X446323Y656101I353J-354D01*
G37*
G36*
G01X219810Y574226D02*
X222337Y576753D01*
X222652Y576806D01*
X222796Y576736D01*
G03X224604Y577121I657J1351D01*
G02X224987Y577300I383J-321D01*
G01X311796D01*
X315333Y573763D01*
X315399Y573491D01*
X315356Y573358D01*
G03X316384Y571456I1432J-455D01*
G02X316750Y570975I-134J-482D01*
G01Y559126D01*
X318346Y557530D01*
X322462D01*
X322557Y557489D01*
G03X323751I597J1378D01*
G01X323846Y557530D01*
X331696D01*
X332740Y556486D01*
Y539444D01*
X330806Y537510D01*
X325266D01*
X323300Y535544D01*
Y497024D01*
X321746Y495470D01*
X225788D01*
X225560Y495598D01*
X225492Y495710D01*
G03X223222Y496060I-1283J-782D01*
G02X221857Y496107I-657J754D01*
G01X219810Y498154D01*
Y527215D01*
X219946Y527447D01*
X220065Y527514D01*
G03Y530132I-737J1309D01*
G01X219946Y530199D01*
X219810Y530431D01*
Y542806D01*
X219914Y542940D01*
G03Y544730I-1163J895D01*
G01X219810Y544864D01*
Y564120D01*
G02X219970Y564487I500J0D01*
G03Y566691I-1020J1102D01*
G02X219810Y567058I340J367D01*
G01Y574226D01*
G37*
G36*
G01X254921Y4500D02*
Y31075D01*
X258194Y34348D01*
Y38904D01*
G02X258694Y39404I500J0D01*
G01X265268D01*
X265352Y39373D01*
G03X266392I520J1409D01*
G01X266476Y39404D01*
X267768D01*
X267852Y39373D01*
G03X268892I520J1409D01*
G01X268976Y39404D01*
X271030D01*
X271158Y39316D01*
G03X272862I852J1237D01*
G01X272990Y39404D01*
X273369D01*
X274047Y38726D01*
Y33083D01*
X275446Y31684D01*
X287993D01*
X289169Y30508D01*
Y4500D01*
G02X288669Y4000I-500J0D01*
G01X255421D01*
G02X254921Y4500I0J500D01*
G37*
G36*
G01X248416Y305352D02*
G03X247663Y307742I-1167J946D01*
G02X247301Y308222I138J481D01*
G01Y313794D01*
G02X247671Y314277I500J0D01*
G03Y317177I-390J1450D01*
G02X247301Y317660I130J483D01*
G01Y325929D01*
X247508Y326198D01*
X247673Y326242D01*
G03X248248Y328851I-383J1452D01*
G02X248182Y329554I319J385D01*
G03X248254Y331376I-1157J958D01*
G02X248302Y332009I409J287D01*
G03X247655Y334486I-1084J1040D01*
G01X247497Y334534D01*
X247301Y334799D01*
Y335695D01*
G02X247522Y336110I500J0D01*
G03Y338604I-837J1247D01*
G01X247418Y338674D01*
X247301Y338894D01*
Y343057D01*
X257238Y352994D01*
G02X258544Y353088I707J-707D01*
G03X260592Y353322I900J1203D01*
G02X260974Y353500I382J-322D01*
G01X318212D01*
G02X318575Y353344I0J-500D01*
G03X320757I1091J1032D01*
G02X321120Y353500I363J-344D01*
G01X321697D01*
G02X322033Y353371I1J-500D01*
G03X324047I1007J1114D01*
G02X324383Y353500I335J-371D01*
G01X332041D01*
X332290Y353337D01*
X332349Y353200D01*
G03X335103I1377J601D01*
G02X335561Y353500I458J-200D01*
G01X339314D01*
X361290Y375476D01*
Y387258D01*
G02X361583Y387713I500J0D01*
G03Y390447I-623J1367D01*
G01X361448Y390508D01*
X361290Y390754D01*
Y394482D01*
G02X361430Y394830I500J1D01*
G03Y396916I-1080J1043D01*
G02X361290Y397264I360J347D01*
G01Y430606D01*
X390924Y460240D01*
X474166D01*
X480380Y454026D01*
Y423561D01*
G02X480235Y423209I-500J0D01*
G03Y421091I1065J-1059D01*
G02X480380Y420739I-355J-352D01*
G01Y337414D01*
X417734Y274768D01*
X417704Y274745D01*
G03X417390Y274431I893J-1207D01*
G01X417367Y274401D01*
X414376Y271410D01*
X404036D01*
X403918Y271481D01*
G03X402378I-770J-1290D01*
G01X402260Y271410D01*
X315644D01*
X311104Y275950D01*
X297035D01*
G02X296603Y276198I0J500D01*
G03X294011I-1296J-759D01*
G01X293943Y276082D01*
X293713Y275950D01*
X262860D01*
G02X262360Y276450I0J500D01*
G01Y292638D01*
X259846Y295152D01*
X259778Y295419D01*
X259818Y295552D01*
G03X256958Y296467I-1438J432D01*
G01X256906Y296315D01*
X256646Y296128D01*
X253796D01*
X248423Y301501D01*
G02X248395Y302177I354J353D01*
G03X248416Y304094I-1146J971D01*
G02Y305352I777J629D01*
G37*
G36*
G01X400085Y601960D02*
X399957Y602048D01*
G03X399761Y602167I-1135J-1649D01*
G01X399663Y602265D01*
Y602618D01*
X398819Y603462D01*
X391277D01*
G02X390777Y603962I0J500D01*
G01Y625133D01*
X394265Y628621D01*
X411124D01*
X422274Y617471D01*
Y602710D01*
G02X421774Y602210I-500J0D01*
G01X407716D01*
X407466Y601960D01*
X400085D01*
G37*
%LPD*%
G75*
G36*
G01X107714Y99535D02*
G03X108424Y98039I1934J2D01*
G02X88315Y73709I-9996J-12214D01*
G02X85848Y95361I10110J12119D01*
G01X85950Y95495D01*
Y95540D01*
X86128Y95719D01*
X86144Y95739D01*
G02X88506Y98103I12283J-9911D01*
G03X89142Y99535I-1298J1434D01*
G01Y105510D01*
G02X107714I9286J0D01*
G01Y99535D01*
G37*
G36*
G01X80874Y697162D02*
X80848Y697322D01*
X80063Y698107D01*
Y698935D01*
X80574Y699446D01*
X80650Y699634D01*
X80649Y699735D01*
G02X87156Y713751I17777J265D01*
G03X87339Y714138I-317J387D01*
G01Y721342D01*
X87486Y721489D01*
X87513Y721643D01*
G02X109339I10913J-1958D01*
G01X109366Y721489D01*
X109513Y721342D01*
Y714138D01*
G03X109696Y713751I500J0D01*
G02X80874Y697162I-11270J-13751D01*
G37*
G36*
G01X397421Y38554D02*
G02X396249Y35852I-3703J1D01*
G01X395926D01*
G03X395426Y35352I0J-501D01*
G01Y35269D01*
G02X392030Y35258I-1709J3285D01*
G01Y35354D01*
G03X391530Y35854I-500J0D01*
G01X391184D01*
G02X391187Y41256I2534J2700D01*
G01X391532D01*
G03X392032Y41756I0J500D01*
G01Y41851D01*
G02X395426Y41839I1685J-3297D01*
G01Y41756D01*
G03X395926Y41256I500J1D01*
G01X396249D01*
G02X397421Y38554I-2531J-2703D01*
G37*
G36*
G01X358051D02*
G02X356879Y35852I-3703J1D01*
G01X356556D01*
G03X356056Y35352I1J-501D01*
G01Y35269D01*
G02X352660Y35258I-1709J3285D01*
G01Y35354D01*
G03X352160Y35854I-500J0D01*
G01X351814D01*
G02X351817Y41256I2534J2700D01*
G01X352162D01*
G03X352662Y41756I0J500D01*
G01Y41851D01*
G02X356056Y41839I1685J-3297D01*
G01Y41756D01*
G03X356556Y41256I501J1D01*
G01X356879D01*
G02X358051Y38554I-2531J-2703D01*
G37*
G36*
G01X698460Y713350D02*
G03X699148Y711871I1934J0D01*
G02X678748Y711822I-10171J-12068D01*
G01X678764Y711835D01*
X679073Y712145D01*
G03X679494Y713350I-1513J1205D01*
G01Y719488D01*
G02X679497Y719700I9483J-28D01*
G01Y720316D01*
X679532Y720351D01*
X679551Y720526D01*
G02X698403I9426J-1038D01*
G01X698422Y720351D01*
X698457Y720316D01*
Y719700D01*
G02X698460Y719488I-9480J-240D01*
G01Y713350D01*
G37*
G36*
G01X614702Y201933D02*
Y192754D01*
X612945Y190997D01*
X610459D01*
X608702Y192754D01*
Y201933D01*
X610459Y203690D01*
X612945D01*
X614702Y201933D01*
G37*
G36*
G01Y186933D02*
Y177754D01*
X612945Y175997D01*
X610459D01*
X608702Y177754D01*
Y186933D01*
X610459Y188690D01*
X612945D01*
X614702Y186933D01*
G37*
G36*
G01X612516Y69078D02*
G02X608614Y65176I-3902J0D01*
G02X604612Y69178I0J4002D01*
G02X612516I3952J0D01*
G01Y69078D01*
G37*
G36*
G01X587858D02*
G02X583956Y65176I-3902J0D01*
G02X579954Y69178I0J4002D01*
G02X587858I3952J0D01*
G01Y69078D01*
G37*
G36*
G01X635583Y193621D02*
X635029D01*
G02X634895I-67J1500D01*
G01X634341D01*
X633959Y194003D01*
G02X633851Y194110I1002J1119D01*
G01X633843Y194119D01*
X633462Y194500D01*
Y195054D01*
G02Y195188I1500J67D01*
G01Y200054D01*
G02Y200188I1500J67D01*
G01Y200742D01*
X633843Y201123D01*
X633851Y201132D01*
G02X633959Y201239I1110J-1012D01*
G01X634341Y201621D01*
X634895D01*
G02X635029I67J-1500D01*
G01X635583D01*
X635965Y201239D01*
G02X636073Y201132I-1002J-1119D01*
G01X636081Y201123D01*
X636462Y200742D01*
Y200188D01*
G02Y200054I-1500J-67D01*
G01Y195188D01*
G02Y195054I-1500J-67D01*
G01Y194500D01*
X636081Y194119D01*
X636073Y194110D01*
G02X635965Y194003I-1110J1012D01*
G01X635583Y193621D01*
G37*
G36*
G01X625421Y178453D02*
X624867D01*
G02X624733I-67J1500D01*
G01X624179D01*
X623797Y178835D01*
G02X623689Y178942I1002J1119D01*
G01X623681Y178951D01*
X623300Y179332D01*
Y179886D01*
G02Y180020I1500J67D01*
G01Y184886D01*
G02Y185020I1500J67D01*
G01Y185574D01*
X623681Y185955D01*
X623689Y185964D01*
G02X623797Y186071I1110J-1012D01*
G01X624179Y186453D01*
X624733D01*
G02X624867I67J-1500D01*
G01X625421D01*
X625803Y186071D01*
G02X625911Y185964I-1002J-1119D01*
G01X625919Y185955D01*
X626300Y185574D01*
Y185020D01*
G02Y184886I-1500J-67D01*
G01Y180020D01*
G02Y179886I-1500J-67D01*
G01Y179332D01*
X625919Y178951D01*
X625911Y178942D01*
G02X625803Y178835I-1110J1012D01*
G01X625421Y178453D01*
G37*
G36*
G01X434136Y385761D02*
Y368570D01*
X421981Y356415D01*
X404791D01*
X392636Y368570D01*
Y385761D01*
X404791Y397916D01*
X421981D01*
X434136Y385761D01*
G37*
G54D50*
X323931Y589733D03*
G54D49*
X218899Y281098D03*
G54D44*
X-44872Y125213D03*
Y141213D03*
Y232533D03*
Y248533D03*
Y738493D03*
Y754493D03*
X-26872Y125213D03*
Y141213D03*
Y232533D03*
Y248533D03*
Y738493D03*
Y754493D03*
G54D46*
X43898Y168544D03*
Y231457D03*
G54D45*
X151969Y98622D03*
G54D52*
X414961D03*
G54D51*
X434102Y232640D03*
Y311875D03*
G54D48*
X25455Y303232D03*
Y356832D03*
G54D47*
X102362Y247244D03*
Y349606D03*
X354331Y247244D03*
Y349606D03*
G54D10*
X-294532Y1044846D03*
X-281332D03*
X-287932D03*
X-267012Y1044916D03*
X-39858Y731383D03*
X-31858D03*
X4390Y533777D03*
X13170Y372673D03*
X18340Y366452D03*
X13120Y375871D03*
X16010Y369168D03*
X21530Y368991D03*
X14140Y391826D03*
X18210Y386530D03*
X13950Y388616D03*
X13390Y397543D03*
X14240Y394866D03*
X19450Y550297D03*
X20650Y546243D03*
X20350Y555807D03*
X18960Y572061D03*
X17876Y578422D03*
X16200Y566921D03*
X21881Y595792D03*
X17020Y592934D03*
X13510Y591939D03*
X15850Y610980D03*
X14500Y601957D03*
X11980Y617956D03*
X15349Y614142D03*
X14550Y628297D03*
X13807Y634826D03*
X9300Y631472D03*
X9240Y638699D03*
X17071Y658951D03*
X11680Y656335D03*
X9260Y658321D03*
X14000Y658369D03*
X14170Y653991D03*
X9360Y653943D03*
X33841Y9183D03*
X23987Y12977D03*
X28104Y30414D03*
X24411Y16186D03*
X36848Y25198D03*
X34149Y44149D03*
X30282Y34564D03*
X30274Y37714D03*
X36588Y32278D03*
X36567Y73145D03*
X39126Y84631D03*
X34008Y91017D03*
X36567Y107988D03*
X32260Y96899D03*
X38280Y362184D03*
X35750Y364593D03*
X33420Y367309D03*
X23860Y366275D03*
X28250Y438740D03*
X37990Y453022D03*
X28250Y472076D03*
X37990Y520218D03*
X38807Y543539D03*
X34140Y540345D03*
X34240Y536966D03*
X38349Y555730D03*
X33231Y556346D03*
X30672Y551245D03*
X23610Y568111D03*
X34440Y597285D03*
X28112Y591718D03*
X36930Y611082D03*
X28270Y602194D03*
X33140Y602232D03*
X28185Y612088D03*
X35862Y617052D03*
X30744Y617898D03*
X29964Y658951D03*
X24168Y655750D03*
X37920Y651828D03*
X45410Y21563D03*
X54860Y16952D03*
X49890Y30392D03*
X51580Y17595D03*
X42205Y21518D03*
X54800Y25547D03*
X43480Y34592D03*
X45578Y50478D03*
X50981Y58681D03*
X46981Y58690D03*
X44010Y55170D03*
X54981Y59420D03*
X41685Y73110D03*
X54101Y74252D03*
X51340Y69181D03*
X46570Y73891D03*
X47510Y109421D03*
X54703Y122796D03*
X46811Y122928D03*
X54062Y257049D03*
X49244Y360352D03*
X40690Y359555D03*
X53340Y393132D03*
X49750Y387305D03*
X51720Y384808D03*
X50840Y395761D03*
X47820Y398827D03*
X49730Y412473D03*
X45530D03*
X52150Y414896D03*
X47900Y414660D03*
X44360Y414915D03*
X49640Y430237D03*
X45410Y430444D03*
X51350Y433695D03*
X47420Y433725D03*
X44360Y433729D03*
X49625Y478472D03*
Y480972D03*
X50330Y497940D03*
X53330D03*
X49645Y491804D03*
Y489304D03*
X47380Y494638D03*
X53622Y509276D03*
X53330Y506417D03*
Y503817D03*
X50330D03*
X53769Y513033D03*
X54988Y518683D03*
X54117Y529098D03*
X49857Y520516D03*
X50630Y529281D03*
X46140Y541712D03*
X41957Y543321D03*
X50140Y550572D03*
X39540Y538464D03*
X50870Y564008D03*
X43467Y555938D03*
X53988Y568748D03*
X49680Y579709D03*
X49620Y574212D03*
X47557Y588971D03*
X44507Y594082D03*
X40908Y589691D03*
X43850Y602797D03*
X39360Y604593D03*
X39370Y600956D03*
X42950Y612487D03*
X50270Y627793D03*
X48540Y624953D03*
X52230Y614907D03*
X51051Y619407D03*
X48060Y621229D03*
X47480Y616848D03*
X50170Y636895D03*
X51038Y643928D03*
X46890Y633564D03*
X53751Y652029D03*
X44640Y651029D03*
X40980Y656396D03*
X49720Y668412D03*
X59524Y25922D03*
X56610Y20553D03*
X66981Y59390D03*
X62981Y59440D03*
X57040Y73421D03*
X60318Y65593D03*
X64190Y72841D03*
X61760Y107321D03*
X55230Y112521D03*
X63900Y112081D03*
X64309Y141882D03*
X68756Y167695D03*
X56190Y170026D03*
X59640Y161376D03*
X57257Y180712D03*
X67853Y180744D03*
X68690Y175589D03*
X55963Y199565D03*
X68930Y197193D03*
X66570Y189983D03*
X57749Y204326D03*
X56383Y218543D03*
X68830Y215817D03*
X63720Y228683D03*
X56936Y223944D03*
X56287Y242872D03*
X63718Y239030D03*
X61945Y267579D03*
X66818Y297483D03*
X57994Y287655D03*
X57624Y366105D03*
X58000Y412641D03*
X66747Y466363D03*
X64050Y465689D03*
X61183Y465314D03*
X61357Y483392D03*
Y480892D03*
Y477892D03*
X61188Y487117D03*
X61676Y502656D03*
Y500156D03*
X61188Y489617D03*
Y492117D03*
X55982Y494543D03*
X64480Y501596D03*
X65438Y510666D03*
X61033Y510705D03*
X61003Y515110D03*
X65478D03*
X56148Y530809D03*
X62253Y522589D03*
X67369Y522993D03*
X70696Y527237D03*
X67260Y546688D03*
X65900Y566403D03*
X66181Y562149D03*
X63930Y560181D03*
X66262Y553344D03*
X65989Y578115D03*
X66036Y574901D03*
X63670Y576040D03*
X57710Y572918D03*
X57070Y580074D03*
X69766Y582525D03*
X57440Y585607D03*
X68630Y599945D03*
X63300Y621755D03*
X61205Y623870D03*
X63570Y613914D03*
X63610Y618917D03*
X61205Y628870D03*
X63490Y630693D03*
X62160Y644091D03*
X59390Y642906D03*
X56240Y630081D03*
X59530Y631704D03*
X63650Y646957D03*
X61600Y653611D03*
X66880Y761625D03*
X59260Y779815D03*
X58840Y783097D03*
X62290Y779629D03*
X67660Y779452D03*
X62730Y782694D03*
X66860Y782716D03*
X60370Y776861D03*
X64790Y776777D03*
X56500Y789667D03*
X79360Y46044D03*
X82065Y73224D03*
X80845Y106859D03*
X76880Y126528D03*
X72890Y154349D03*
X76030Y156152D03*
X81030Y172605D03*
X78850Y157866D03*
X85010Y171679D03*
X71510Y164548D03*
X74470Y175666D03*
X82553Y185431D03*
X82030Y191733D03*
X75236Y188946D03*
X75359Y201109D03*
X85876Y218939D03*
X78190Y214642D03*
X86172Y213852D03*
X75560Y218513D03*
X73870Y205758D03*
X72150Y225148D03*
X78614Y229920D03*
X79217Y232861D03*
X83390Y235665D03*
X79142Y237920D03*
X86479Y249259D03*
X77239Y260814D03*
X81210Y261337D03*
X81165Y257717D03*
X79544Y267579D03*
X78373Y276029D03*
X78220Y281745D03*
X78207Y279092D03*
X72190Y297395D03*
X82368Y297135D03*
X72368Y287906D03*
X82560Y288099D03*
X82600Y285426D03*
X77368Y299206D03*
X73917Y385722D03*
X74058Y389621D03*
X83084D03*
X74031Y393857D03*
X73868Y397913D03*
X83245D03*
X85951Y410263D03*
X74291Y486665D03*
X83455Y489485D03*
Y491985D03*
X85955Y489485D03*
Y491985D03*
X83455Y494485D03*
X85955D03*
X83536Y498308D03*
X81635Y517104D03*
Y513104D03*
X81174Y503587D03*
X85346Y512295D03*
X73057Y515286D03*
X72635Y508991D03*
X81491Y533191D03*
X81635Y521104D03*
X82031Y523928D03*
X72216Y540493D03*
X80318Y544311D03*
X81585Y536382D03*
X80318Y541026D03*
X84990Y563286D03*
X82140Y560758D03*
X81980Y556851D03*
X81516Y577905D03*
X83030Y582656D03*
X85140Y585213D03*
X73130Y601599D03*
X73180Y611184D03*
X75380Y608914D03*
Y603914D03*
X80630Y689682D03*
X82847Y716068D03*
X82736Y791695D03*
Y788695D03*
X70925D03*
Y791695D03*
X97830Y66508D03*
X98531Y121340D03*
X102257Y167955D03*
X90878Y177967D03*
X90905Y199733D03*
X101449Y194368D03*
X86560Y205852D03*
X96168Y231618D03*
X98700Y234650D03*
X96990Y223043D03*
X101020Y223348D03*
X88399Y244041D03*
X93200Y300734D03*
X99968Y367705D03*
X95968Y367814D03*
X95951Y376661D03*
X98410Y421908D03*
X98470Y418834D03*
X101650Y428745D03*
Y425552D03*
Y433296D03*
Y436075D03*
X101590Y446203D03*
X101650Y443038D03*
X86726Y501997D03*
X88563Y491984D03*
Y489484D03*
Y494484D03*
X86695Y498180D03*
X91458Y511853D03*
X87721Y505817D03*
X92422Y531081D03*
X95660Y531362D03*
X98803Y531597D03*
X97268Y537055D03*
X97366Y542897D03*
X88200Y568111D03*
X98370Y619252D03*
X94070Y618986D03*
Y613841D03*
X97790Y613797D03*
X96200Y616325D03*
X95350Y644088D03*
X95310Y647481D03*
X98480Y646217D03*
X98410Y648878D03*
Y680541D03*
X100223Y733207D03*
X89810Y765905D03*
X97390Y766435D03*
X98590Y782494D03*
X97180Y786472D03*
X94547Y788695D03*
Y791695D03*
X112386Y71874D03*
X115628Y104405D03*
X111220Y160923D03*
X106090Y167615D03*
X112530Y186363D03*
X106760Y175370D03*
X114920Y179082D03*
X108910Y193194D03*
X106517Y210796D03*
X104550Y262359D03*
X104270Y265662D03*
X110230Y360735D03*
X103151Y373340D03*
X110230Y363235D03*
X117030Y389978D03*
X110490Y397362D03*
X116960Y394023D03*
X103750Y402740D03*
X103810Y405876D03*
X103870Y399604D03*
X108235Y401017D03*
X111120Y401084D03*
X115727Y405844D03*
X113412Y404826D03*
X113504Y407673D03*
X107531Y394023D03*
X114207Y417910D03*
Y414910D03*
X105670Y411262D03*
X117980Y451981D03*
X118020Y455079D03*
X114072Y480964D03*
X115516Y485696D03*
X110400Y502223D03*
X110436Y499681D03*
X110472Y496888D03*
X113337Y502080D03*
X113372Y496888D03*
X113301Y499574D03*
X117026Y488316D03*
X108026Y492500D03*
X114372Y518898D03*
X109972Y509321D03*
X112575Y532934D03*
X113912Y541144D03*
X114005Y544358D03*
X112627Y536697D03*
X109640Y611890D03*
X109410Y621425D03*
X109500Y616724D03*
X109260Y644687D03*
Y648989D03*
X117790Y667235D03*
X115748Y716275D03*
X106358Y785790D03*
X102421Y782191D03*
X110295Y785734D03*
Y782191D03*
X116370Y785941D03*
X104300Y773100D03*
X106650Y779581D03*
X102421Y785938D03*
X114232Y791695D03*
Y788695D03*
X129860Y14571D03*
X130195Y19162D03*
X131474Y43439D03*
X131068Y76588D03*
X126220Y80364D03*
Y83291D03*
X125480Y91163D03*
X132400Y88153D03*
X129580Y86837D03*
X129780Y92580D03*
X124150Y94643D03*
X128330Y98360D03*
X130350Y130400D03*
Y134167D03*
X126460Y250160D03*
X129650Y250414D03*
X126570Y256194D03*
X129650Y255414D03*
X129660Y279890D03*
X130310Y269174D03*
X130324Y272096D03*
Y277096D03*
X123160Y287060D03*
X129610Y287115D03*
X123960Y283696D03*
X128960D03*
X125050Y384546D03*
X122120Y386736D03*
X126300Y390369D03*
X122729Y398001D03*
X127729D03*
X125229D03*
X128226Y413925D03*
X125726D03*
X123226D03*
X129028Y425593D03*
X121080Y460060D03*
X124040Y459746D03*
X127060Y460040D03*
X126377Y466738D03*
X121360Y472028D03*
X118720Y471989D03*
X126072Y480864D03*
X130794Y493910D03*
X133731D03*
X127705Y489431D03*
X125105D03*
X119326Y489706D03*
X121968Y488481D03*
X122018Y516353D03*
X118124Y510811D03*
X133138Y510114D03*
X121644Y509398D03*
X130596Y510042D03*
X124652Y509398D03*
X130703Y512549D03*
X130844Y515128D03*
X128087Y513874D03*
X124279Y523691D03*
X132960Y550005D03*
X125340Y558090D03*
X120300Y572512D03*
X133590Y588438D03*
X130790Y595613D03*
X128240Y666583D03*
X120909Y674490D03*
X132190Y662616D03*
X121070Y670509D03*
X132050Y671817D03*
X129607Y686735D03*
X133607Y686699D03*
X130260Y679836D03*
X132438Y704733D03*
X133490Y695470D03*
X126220Y720949D03*
X120357Y738889D03*
X132334Y732982D03*
X120322Y742187D03*
X123518Y742030D03*
X119900Y754021D03*
X125600Y759000D03*
X125960Y785699D03*
X120090Y780618D03*
X130850Y782456D03*
X118169Y783857D03*
X130660Y785601D03*
X127290Y781982D03*
X122720Y785051D03*
X137500Y25494D03*
X141490Y19267D03*
X137872Y29551D03*
X147427Y30367D03*
X146380Y20345D03*
X147461Y38078D03*
X147497Y42983D03*
X139931Y40842D03*
X139932Y35310D03*
X145210Y60154D03*
X149157Y60010D03*
X135050Y53493D03*
X137540Y58255D03*
X143857Y51943D03*
X149025Y51720D03*
X146558Y74863D03*
X135290Y87664D03*
X140350Y81347D03*
X135640Y134167D03*
X135590Y130449D03*
X147570Y249033D03*
X147160Y242219D03*
X144400Y244061D03*
Y247561D03*
X148330Y258806D03*
X141682Y269829D03*
X143150Y281123D03*
X145200Y276468D03*
X138930Y278965D03*
X148350Y281769D03*
X134540Y267786D03*
X137925Y290987D03*
X137990Y296735D03*
X139950Y293835D03*
X136130Y305640D03*
X137091Y301799D03*
X149020Y303498D03*
X145720Y311336D03*
X135730Y314543D03*
X134768Y319043D03*
X135224Y323543D03*
X146100D03*
X145580Y316836D03*
X136506Y332193D03*
X144058Y376025D03*
X137889Y403348D03*
X141800Y404481D03*
X141847Y401820D03*
X135088Y405060D03*
X135181Y402121D03*
X145295Y404388D03*
X145284Y401507D03*
X135507Y421367D03*
X142239Y422346D03*
X139395Y425090D03*
X138437Y435930D03*
Y438430D03*
X147820Y441929D03*
X147576Y445279D03*
Y447779D03*
Y450279D03*
X138437Y440930D03*
X135300Y468444D03*
X146240Y472111D03*
X139365Y516636D03*
X139402Y513707D03*
X149477Y532733D03*
X144120Y547577D03*
X146920Y547677D03*
X145020Y576001D03*
X143252Y573105D03*
X145550Y588088D03*
X149050Y588044D03*
X141260Y588175D03*
X141190Y597685D03*
X145880Y584125D03*
X144710Y598135D03*
X136420Y599352D03*
X147753Y627557D03*
X145750Y630254D03*
X148200Y669205D03*
X140110Y675907D03*
X147750Y687539D03*
X143823Y682907D03*
X134450Y682978D03*
X139158Y686725D03*
X135280Y679212D03*
X138726Y696707D03*
X138198Y712628D03*
X134777Y738726D03*
Y734726D03*
X134753Y726161D03*
X137070Y728012D03*
X144631Y735955D03*
X134720Y742382D03*
X147290Y744113D03*
X145040Y740741D03*
X139600Y781281D03*
X135470Y781697D03*
X135610Y784521D03*
X139680Y784596D03*
X149450Y780429D03*
X146150Y783820D03*
X145570Y780580D03*
X141791Y788695D03*
Y791695D03*
X150787Y9246D03*
X158181Y11978D03*
X153863Y15176D03*
X164139Y13027D03*
X154592Y21173D03*
X157877Y30674D03*
X152810Y29921D03*
X158165Y21300D03*
X150592Y20974D03*
X152412Y38112D03*
X152366Y42983D03*
X156255Y45743D03*
X159861Y36134D03*
X160731Y41038D03*
X162350Y42984D03*
X152789Y53124D03*
X157659Y47891D03*
X157010Y58963D03*
X164550Y61239D03*
X156440Y74863D03*
X161221Y89447D03*
X151618Y83343D03*
X160040Y108844D03*
X164280Y101810D03*
X162130Y129344D03*
X164490Y127110D03*
X159190Y127781D03*
X163518Y243987D03*
X162317Y249877D03*
X152990Y248096D03*
X157690Y249918D03*
X161918Y254287D03*
X160449Y259605D03*
X154546Y256986D03*
X162484Y276599D03*
X152634Y276809D03*
X158583Y285548D03*
X161918Y293869D03*
X161767Y287242D03*
X149721Y292987D03*
X152733Y288517D03*
X158076Y290635D03*
X162181Y303075D03*
X161687Y310355D03*
X154581Y308767D03*
X162063Y327940D03*
X162017Y324389D03*
X159564Y328013D03*
X161513Y317143D03*
X151230Y330164D03*
X150918Y318134D03*
X159285Y336220D03*
X150510Y336306D03*
X156448Y336629D03*
X162071Y336947D03*
X164418Y348187D03*
X152058Y376016D03*
X160058Y375818D03*
X150524Y382808D03*
X165290Y385948D03*
X151820Y385554D03*
X150902Y379714D03*
X160886Y380294D03*
X160710Y384044D03*
X161640Y403286D03*
X162940Y406188D03*
X161577Y436834D03*
X161563Y432521D03*
X154370Y449930D03*
X151145Y469456D03*
X150547Y459363D03*
X163377Y484538D03*
X152554Y494027D03*
X158406Y500016D03*
X162335Y512456D03*
X159196Y515612D03*
X159179Y521893D03*
X154126Y524411D03*
X154475Y530422D03*
X159180Y528227D03*
X162335Y543954D03*
X159185Y537654D03*
X162336Y550253D03*
X155109Y561153D03*
X164259Y557273D03*
X154140Y577815D03*
X158430Y568437D03*
X161280Y581585D03*
X162786Y568599D03*
X151900Y590454D03*
X156480Y583315D03*
X153527Y597138D03*
X160699Y587904D03*
X150380Y602885D03*
X153712Y610917D03*
X153330Y599935D03*
X153422Y603043D03*
X153955Y620760D03*
X157963Y643289D03*
Y633735D03*
X162668Y631897D03*
X162530Y643235D03*
Y636435D03*
X164812Y662579D03*
X149860Y726626D03*
X154970Y736966D03*
X161981Y730784D03*
X158881D03*
X162640Y743927D03*
X158970D03*
X154400Y744337D03*
X155230Y740259D03*
X163138Y778565D03*
X160480Y777583D03*
X155170Y780656D03*
X164630Y781222D03*
X153320Y783499D03*
X160320Y786346D03*
X149810Y783858D03*
X179235Y7369D03*
X171310Y12450D03*
X171666Y7449D03*
X175280Y12401D03*
X174166Y7449D03*
X166639Y13027D03*
X168961Y27073D03*
X165959Y27133D03*
X173110Y26877D03*
X180907Y27544D03*
X176090Y26906D03*
X180159Y40661D03*
X165336Y46126D03*
X177224Y49101D03*
X174724D03*
X177224Y51601D03*
X174724D03*
X172224Y49101D03*
Y54101D03*
X177224D03*
X174724D03*
X172224Y51601D03*
X169149Y50968D03*
X168040Y61462D03*
X177757Y88271D03*
X168308Y88412D03*
X177733Y91967D03*
X167383Y93147D03*
X180990Y108770D03*
X177210Y97657D03*
X165690Y98835D03*
X171950Y105105D03*
X168850Y99251D03*
X169510Y106579D03*
X173900Y97662D03*
X177680Y101764D03*
X174710Y105699D03*
X167127Y120603D03*
X174213Y120569D03*
X177763Y121057D03*
X168170Y123367D03*
X173170D03*
X180510Y233307D03*
X178040Y228978D03*
X174138Y243873D03*
X171320Y243601D03*
X167467Y243242D03*
X167483Y239914D03*
X177891Y249324D03*
X171668Y256287D03*
X175756Y257668D03*
X173263Y262589D03*
X176301Y262624D03*
X167322Y255855D03*
X167698Y260617D03*
X178929Y262244D03*
X175110Y260412D03*
X175118Y274287D03*
X170617Y267326D03*
X175318Y278687D03*
X170510Y275522D03*
X178025Y279018D03*
X174078Y271435D03*
X170829Y271452D03*
X178941Y270160D03*
X177470Y294933D03*
X180254Y295023D03*
X175162Y293934D03*
X175659Y286984D03*
X178810Y287263D03*
X174148Y289289D03*
X176037Y309845D03*
X180254Y310663D03*
X178812Y324259D03*
X180342Y316469D03*
X175330Y318552D03*
X166189Y335285D03*
X167383Y341306D03*
X177359Y332553D03*
X174876Y336549D03*
X168110Y350642D03*
X177604Y355155D03*
X177720Y352522D03*
X177029Y347811D03*
X177672Y358103D03*
X176058Y376568D03*
X168058Y376035D03*
X167951Y380551D03*
X175290Y389582D03*
X174500Y383383D03*
X178660Y388418D03*
X171934Y386364D03*
X175155Y380727D03*
X180430Y392969D03*
X175663Y386424D03*
X176371Y404721D03*
X180440Y398056D03*
X172760Y406540D03*
X170506Y424127D03*
X175993Y414924D03*
X167527Y420268D03*
X179562Y424001D03*
X173381Y424005D03*
X178232Y430642D03*
X178217Y435317D03*
X173151Y427552D03*
X170683Y436834D03*
X170361Y428595D03*
X172944Y448387D03*
X170444D03*
X177525Y451946D03*
X180125D03*
X178961Y448138D03*
X176220Y448247D03*
X171616Y467804D03*
X179857Y477790D03*
X168370D03*
X169728Y487664D03*
X168189Y514331D03*
X178085Y512456D03*
X173252Y515693D03*
X165707Y506156D03*
X172087Y510536D03*
X169615Y519216D03*
X178094Y531365D03*
X166297Y532416D03*
X169491Y529702D03*
X166837Y523486D03*
X174395Y527975D03*
X171606Y527511D03*
X168243Y542706D03*
X174930Y547106D03*
X169157Y548676D03*
X169293Y562358D03*
X173163Y551903D03*
X169444Y558757D03*
X167105Y552882D03*
X178083Y553402D03*
X172889Y562710D03*
X171053Y569411D03*
X175330Y578535D03*
X166930Y578435D03*
X166786Y569056D03*
X175386Y569589D03*
X179740Y568951D03*
X172430Y584035D03*
X177830Y583535D03*
X166570Y583874D03*
X166605Y587860D03*
X178416Y587849D03*
X179532Y600437D03*
X173432D03*
X165832Y600337D03*
Y606037D03*
Y613137D03*
X172532Y619537D03*
X178632Y619437D03*
X165832D03*
X179120Y639615D03*
X169930Y635329D03*
X172510Y639771D03*
X167530Y631935D03*
X174479Y631986D03*
X177038Y647135D03*
X166388Y647435D03*
X171180Y652009D03*
X171270Y655650D03*
X179180Y675205D03*
X174761Y663816D03*
X167810Y668131D03*
X178982Y688631D03*
X171180Y683815D03*
X178278Y705976D03*
Y701976D03*
Y697976D03*
Y709976D03*
X180820Y717914D03*
X171154Y715673D03*
X169531Y710542D03*
X175463Y720245D03*
X171689Y728920D03*
X165599Y730476D03*
X174954Y728404D03*
X177920Y739302D03*
X167568Y743335D03*
X177224Y777765D03*
X169350Y785470D03*
X172600Y780150D03*
X169860Y782086D03*
X167350Y778074D03*
X173287Y791695D03*
Y788695D03*
X189235Y7369D03*
X191735D03*
X181735D03*
X194825Y10196D03*
X194861Y12952D03*
X183407Y27544D03*
X188634Y27860D03*
X191596Y27620D03*
X184843Y88467D03*
X191930Y88507D03*
X184928Y91847D03*
X189928D03*
X196653Y91837D03*
X196000Y95568D03*
X195473Y108767D03*
X184170Y95213D03*
X186060Y100103D03*
X196493Y105637D03*
X183013Y98813D03*
X190100Y99701D03*
X188203Y104567D03*
X196010Y125188D03*
X186730Y121202D03*
X194463Y122631D03*
X188821Y232784D03*
X184050Y230139D03*
X183550Y235060D03*
X193677Y243855D03*
X189192Y243061D03*
X184318Y247612D03*
X188899Y240208D03*
X195126Y249955D03*
X184296Y241098D03*
X188899Y236808D03*
X194056Y256697D03*
X193735Y265857D03*
X188442Y252643D03*
X184829Y259139D03*
X181176Y257643D03*
X188658Y256870D03*
X184117Y264852D03*
X181602Y262656D03*
X186873Y263697D03*
X185798Y256760D03*
X186873Y260697D03*
X194693Y259197D03*
Y262197D03*
X190918Y277687D03*
X185991Y279041D03*
X186118Y270787D03*
X183440Y269816D03*
X194205Y271034D03*
X191860Y270148D03*
X183198Y278034D03*
X183698Y285693D03*
X193557Y294428D03*
X187812Y286352D03*
X184812Y292979D03*
X186254Y295023D03*
X192298Y286183D03*
X194771Y302176D03*
X193812Y308619D03*
X195254Y310663D03*
X184754Y302843D03*
X186254Y310663D03*
X183254D03*
X193313Y325492D03*
X186296Y326366D03*
X186350Y317116D03*
X196476Y317042D03*
X183228Y317023D03*
X193957Y317064D03*
X191159Y317171D03*
X190557Y325701D03*
X187404Y343998D03*
X192293Y340792D03*
X185195Y332852D03*
X184367Y337792D03*
X192230Y337322D03*
X192040Y333606D03*
X186925Y355812D03*
X192519Y352761D03*
X186908Y352760D03*
X184058Y376479D03*
X195420Y372406D03*
X194231Y390267D03*
X184927Y383876D03*
X192681Y377554D03*
X193590Y383383D03*
X185074Y380726D03*
X194330Y396425D03*
X192676Y402961D03*
X196273Y403152D03*
X182771Y424013D03*
X185271D03*
X182771Y421513D03*
X185271D03*
X190700Y418325D03*
X182132Y418327D03*
X182877Y430662D03*
X182879Y435312D03*
X192527Y429049D03*
X189077Y438281D03*
X192069Y444852D03*
X184523Y441915D03*
X181923Y445044D03*
Y442544D03*
X185747Y487664D03*
X193500Y489796D03*
X181231Y512455D03*
X184843Y533995D03*
X188640Y530667D03*
X191457Y531553D03*
X193466Y546886D03*
X186841Y545372D03*
X181232Y553402D03*
X181491Y557436D03*
X188654Y573395D03*
X193080Y581235D03*
X191500Y571956D03*
X182480Y566819D03*
X196740Y589735D03*
X181330Y587535D03*
X185032Y606737D03*
X184932Y600537D03*
X185032Y612937D03*
X184932Y619437D03*
X192130Y632235D03*
X184748Y639687D03*
X182480Y634585D03*
X191480Y639135D03*
X182353Y631612D03*
X196410Y650155D03*
X187410Y649715D03*
Y659705D03*
X191910Y650055D03*
X188200Y672526D03*
X196463Y685036D03*
X182163Y684555D03*
X185993Y682670D03*
X191542Y691925D03*
X194508Y704476D03*
X187798Y704513D03*
X181744Y694829D03*
X181950Y698191D03*
X190375Y695624D03*
X185440Y712499D03*
X196144Y712602D03*
X187744Y708356D03*
X191930Y712624D03*
X188566Y722353D03*
X183566D03*
X193566Y722333D03*
X196079Y723943D03*
X194440Y735623D03*
X189940Y735681D03*
X185440D03*
X182674Y730521D03*
X191150Y724108D03*
X186164Y724134D03*
X192949Y771020D03*
X182500Y780786D03*
X189770Y778082D03*
X204785Y13762D03*
X204978Y10605D03*
X201849Y15292D03*
X198577Y15374D03*
X199016Y88434D03*
X206103Y88207D03*
X204003Y91247D03*
X202560Y107797D03*
X210203Y108457D03*
X206273Y98364D03*
X200480Y97687D03*
X212423Y104957D03*
X208908Y96975D03*
X205903Y101477D03*
X199993Y103637D03*
X210623Y121267D03*
X207070Y179744D03*
X207154Y175212D03*
X207041Y184502D03*
X207070Y188978D03*
X212020Y234359D03*
X205535Y234497D03*
Y228682D03*
X211935Y230585D03*
X198296Y232699D03*
X211935Y244085D03*
X198685Y240785D03*
X211935Y237385D03*
Y240785D03*
X205566Y243497D03*
X205271Y240209D03*
X198685Y237385D03*
Y244085D03*
X211028Y255696D03*
X210333Y265197D03*
X208129Y257519D03*
X206144Y252477D03*
X208289Y263639D03*
X210305Y259330D03*
Y262289D03*
X201994Y261248D03*
X200977Y256305D03*
X202402Y263713D03*
X200469Y259139D03*
X201518Y265990D03*
X208226Y269697D03*
X201667Y274542D03*
X199509Y278094D03*
X210303Y268227D03*
X206299Y281098D03*
X210303Y271227D03*
X203149Y281098D03*
X201518Y268887D03*
X206299Y290548D03*
X206319Y296863D03*
X203149Y290548D03*
X206299Y293698D03*
Y312598D03*
Y306298D03*
Y303148D03*
X209449Y312598D03*
X203166Y312577D03*
X202525Y299358D03*
X209300Y322800D03*
X207310Y330149D03*
X206299Y315748D03*
X203058Y315593D03*
X200211Y321446D03*
X200572Y323920D03*
X208000Y325200D03*
X208700Y328000D03*
X200590Y327615D03*
X208485Y332356D03*
X200905Y333776D03*
X201489Y336207D03*
Y339107D03*
X197243Y344518D03*
X206817Y358874D03*
X207274Y353124D03*
X198987Y353137D03*
X206657Y356116D03*
X202823Y376922D03*
X197938Y376839D03*
X206973Y361900D03*
X200439Y390168D03*
X203880Y385272D03*
X205790Y387003D03*
X200488Y396425D03*
X201267Y403294D03*
X210880Y402359D03*
X206380Y402201D03*
X200039Y448750D03*
Y451350D03*
X197809Y469953D03*
X204584Y462478D03*
X197161Y465628D03*
X200434Y478345D03*
X200459Y487253D03*
X208710Y500856D03*
X211379Y501904D03*
X211609Y516553D03*
X205257Y528822D03*
X211287Y528547D03*
X212342Y536729D03*
X199539Y537112D03*
X204309Y539953D03*
X205286Y551130D03*
X202486D03*
X211240Y572893D03*
X210040Y576893D03*
X201510Y576885D03*
X197730Y572893D03*
X197709Y567464D03*
X209590Y580893D03*
X210790Y566926D03*
X209940Y584893D03*
X197230Y595335D03*
X198890Y584105D03*
X207178Y591595D03*
X211760Y610915D03*
X207476Y608936D03*
X207010Y602472D03*
X196907Y605012D03*
X197030Y598535D03*
X204024Y604135D03*
Y609135D03*
X208904Y611515D03*
X200380Y629085D03*
X199786Y618893D03*
X211862Y617709D03*
X202510Y624005D03*
X197230Y615435D03*
X197130Y626135D03*
X208904Y616515D03*
X197480Y639815D03*
X203065Y638700D03*
X205221Y630886D03*
X200910Y659735D03*
Y650155D03*
X205410Y650035D03*
X209238Y674373D03*
X202450Y663633D03*
X199510Y663158D03*
X205410Y661200D03*
X211560Y670575D03*
X202518Y673273D03*
X197889Y671226D03*
X210824Y692266D03*
X199590Y682868D03*
X197582Y703474D03*
X200692Y704081D03*
X199350Y692724D03*
X211236Y695586D03*
X197243Y697899D03*
X210023Y712842D03*
X201663Y712694D03*
X198940Y712499D03*
X198566Y722353D03*
X209017Y722344D03*
X203611Y722303D03*
X205440Y712510D03*
X211897Y723870D03*
X201411Y708231D03*
X212440Y735829D03*
X198940Y735681D03*
X207940D03*
X203440D03*
X205883Y724373D03*
X200817Y724180D03*
X199760Y763929D03*
X202050Y784919D03*
X206210Y771577D03*
X212350Y773283D03*
X200846Y788695D03*
Y791695D03*
X225990Y21219D03*
X221990D03*
X221600Y66317D03*
X225600D03*
X213190Y88414D03*
X220276Y88440D03*
X214573Y93771D03*
X215773Y90147D03*
X222983Y91587D03*
X220200Y93561D03*
X226620Y89385D03*
X219095Y108675D03*
X217040Y103121D03*
X214320Y101978D03*
X220983Y106174D03*
X213908Y96975D03*
X219510Y101338D03*
X226713Y122007D03*
X228138Y125802D03*
X226010Y233542D03*
X217135Y230585D03*
Y244085D03*
X226010Y240342D03*
X217135Y240785D03*
Y237385D03*
X219772Y252659D03*
X215761Y252833D03*
X224794Y256754D03*
X218153Y260697D03*
Y263697D03*
X223929Y263639D03*
X216512Y258490D03*
X225973Y262197D03*
X216109Y265139D03*
Y262139D03*
X218508Y256664D03*
X225973Y259197D03*
X225199Y281098D03*
X216109Y274139D03*
X212599Y281098D03*
X218899D03*
X224357Y273228D03*
X216109Y271139D03*
X215749Y281098D03*
X213138Y274187D03*
X212599Y290548D03*
X225199Y287398D03*
X212599Y293698D03*
X222049Y290548D03*
X215749Y293698D03*
Y287398D03*
X225199Y309448D03*
Y299998D03*
Y303148D03*
X222049Y309448D03*
X212599Y299998D03*
Y303148D03*
X222049Y312598D03*
X218899Y309448D03*
X222049Y303148D03*
X218899Y299998D03*
Y303148D03*
X218947Y312617D03*
X215100Y322700D03*
X217129Y327207D03*
X215085Y325649D03*
X212600Y319100D03*
X217129Y324207D03*
X224949Y328707D03*
X225199Y315748D03*
X224585Y322992D03*
X224711Y325922D03*
X217129Y336207D03*
X217067Y339542D03*
X217129Y333207D03*
X223010Y344242D03*
X223166Y338842D03*
X222911Y333155D03*
X224996Y334617D03*
X223095Y336241D03*
X221280Y340579D03*
X228057Y352837D03*
X222777Y353066D03*
X214888Y352909D03*
X222974Y356134D03*
X214657Y356205D03*
X214007Y362701D03*
X222225Y364031D03*
X227745Y368007D03*
X223561Y385108D03*
X214008Y385165D03*
X221438Y390655D03*
X224108Y388029D03*
X214786Y388603D03*
X218090Y390891D03*
X216633Y384989D03*
X215120Y399654D03*
X214406Y395539D03*
X223085Y401702D03*
X213710Y402237D03*
X226276Y460704D03*
X213994Y466054D03*
X228242Y463681D03*
X223953Y463550D03*
X212809Y479053D03*
X215409Y479253D03*
X222419Y479933D03*
X218040Y473853D03*
X223786Y476638D03*
X226255Y472579D03*
X216209Y488853D03*
X213209D03*
X224209Y494928D03*
X219309Y489353D03*
X222209D03*
X227284Y502591D03*
X224209Y491853D03*
X217609Y516353D03*
X219328Y528823D03*
X223376Y523322D03*
X215946Y544202D03*
X221591Y563371D03*
X223561Y561475D03*
X218950Y565589D03*
X223453Y578087D03*
X216590Y570850D03*
X220428Y580271D03*
X227100Y580916D03*
X218859Y593093D03*
X225100Y597453D03*
X219960Y596373D03*
X219296Y604811D03*
X219960Y601373D03*
X215699Y625977D03*
X215604Y621977D03*
X215985Y633977D03*
X216107Y637977D03*
X215948Y629977D03*
X221129Y642363D03*
X228290Y629893D03*
X218308Y635939D03*
X225179Y642614D03*
X215768Y671993D03*
X218240Y674433D03*
X225237Y671772D03*
X212635Y665604D03*
X224289Y680081D03*
X224360Y684366D03*
X213365Y692151D03*
X224060Y690317D03*
X224336Y687758D03*
X223707Y695436D03*
X220580Y692876D03*
X223741Y700554D03*
X221340Y697995D03*
X226610Y713482D03*
X217530Y715305D03*
X221320Y720698D03*
X213310Y719064D03*
X222710Y713706D03*
X216820Y723301D03*
X227650Y720791D03*
X224410Y719970D03*
X216940Y736063D03*
X221440Y735934D03*
X225940Y724061D03*
Y733671D03*
Y736437D03*
X218270Y785657D03*
X220960Y778561D03*
X226670Y773299D03*
X220532Y788695D03*
Y791695D03*
X212658D03*
Y788695D03*
X241990Y21219D03*
X229990D03*
X237600Y66317D03*
X241600D03*
X229600D03*
X233600D03*
X236360Y93931D03*
X236812Y88698D03*
X229725Y88719D03*
X235113Y91307D03*
X231013Y91547D03*
X243373Y88767D03*
X239563Y92077D03*
X243730Y103057D03*
X240355Y108757D03*
X239500Y100925D03*
X231910Y105731D03*
X235190Y96905D03*
X230643Y108497D03*
X234243Y100156D03*
X233083Y94817D03*
X237773Y103607D03*
X242913Y106157D03*
X233268Y121742D03*
X233138Y125802D03*
X232948Y234047D03*
X236710Y244042D03*
X242460Y237591D03*
X237654Y249719D03*
X231710Y243642D03*
Y240242D03*
X231749Y265139D03*
X239569Y257639D03*
X241613Y262197D03*
X239569Y266639D03*
X241613Y259197D03*
X237594Y252754D03*
X239569Y263639D03*
X233793Y263697D03*
X231749Y262139D03*
X233793Y260697D03*
X239569Y260639D03*
X231749Y259139D03*
X240910Y274742D03*
X233793Y269697D03*
X239569Y269639D03*
X232118Y271587D03*
X241613Y271197D03*
Y268197D03*
X228821Y274197D03*
X231648Y274243D03*
X237799Y290548D03*
Y284248D03*
X231499Y287398D03*
X240949Y296848D03*
X237800Y299998D03*
X231499Y309448D03*
X237799Y303148D03*
X234649D03*
X237799Y306298D03*
X240925Y306257D03*
X240949Y299998D03*
Y303148D03*
X241258Y319123D03*
X231567Y321742D03*
X232782Y327096D03*
X230725Y325649D03*
X238545Y327149D03*
X240374Y328960D03*
X240511Y325517D03*
X240692Y344204D03*
X233055Y339936D03*
X230725Y331649D03*
X238548Y333149D03*
X230725Y334547D03*
X240598Y334642D03*
X240218Y338010D03*
X231144Y338225D03*
X238560Y336136D03*
X232769Y333207D03*
X232804Y336181D03*
X239290Y340428D03*
X233697Y353961D03*
X238084Y355992D03*
X228419Y356855D03*
X233635Y357082D03*
X230010Y373300D03*
X237578Y369584D03*
X233136Y367070D03*
X243078Y368384D03*
X231257Y362218D03*
X243940Y390885D03*
X236687Y385234D03*
X232172Y388814D03*
X228729Y385227D03*
X241451Y392147D03*
X236412Y387722D03*
X231223Y391424D03*
X239546Y390528D03*
X239228Y393291D03*
X236430Y393470D03*
X232647Y396011D03*
X240599Y440053D03*
X235319Y464362D03*
X231461Y462591D03*
X243471Y460292D03*
X238430Y460338D03*
X233309Y472553D03*
X237609Y472453D03*
X241909Y472553D03*
X234209Y480953D03*
X228604Y479682D03*
X233626Y512040D03*
X236776Y534087D03*
X233626Y524639D03*
X236776Y540386D03*
X235307Y566357D03*
X242915Y576539D03*
X243209Y574018D03*
X239269Y597128D03*
X229809Y583627D03*
X229269Y597682D03*
X242830Y597415D03*
X234370Y593242D03*
X242796Y589749D03*
X236780Y628738D03*
X229199Y642180D03*
X243693Y632254D03*
X238420Y642148D03*
X234500Y637685D03*
X243743Y636514D03*
X229584Y652668D03*
X237451Y652761D03*
X241670Y652558D03*
X233584Y652519D03*
X243596Y671772D03*
X229895Y671672D03*
X239168D03*
X237275Y679609D03*
X240493Y692678D03*
X239084Y696252D03*
X233954Y697395D03*
X236120Y704173D03*
X238348Y712469D03*
X242680Y712337D03*
X234960Y714064D03*
X239210Y720040D03*
X234910Y720816D03*
X243900Y724662D03*
X239440Y736140D03*
X230440Y736412D03*
X234940Y724325D03*
Y733355D03*
X243940Y736412D03*
X239500Y733523D03*
X230440Y724242D03*
X234940Y736392D03*
X236180Y786517D03*
X242230Y774803D03*
X234011Y772902D03*
X240217Y788695D03*
Y791695D03*
X232343D03*
Y788695D03*
X249990Y21219D03*
X245990D03*
X258103Y53688D03*
X257500Y56117D03*
X253810Y63244D03*
X245600Y66317D03*
X249600D03*
X246073Y92197D03*
X256573Y94097D03*
X247870Y105821D03*
X252683Y105867D03*
X253558Y95038D03*
X256133Y99347D03*
X248558Y95038D03*
X259030Y123727D03*
X259443Y120773D03*
X249453Y114307D03*
X255287Y226709D03*
X254221Y230582D03*
X256492Y222466D03*
X254181Y234521D03*
X257950Y236924D03*
X254418Y240407D03*
X255209Y260639D03*
X255359Y266557D03*
X247389Y259139D03*
X256553Y256881D03*
X249433Y263697D03*
Y260697D03*
X256916Y262609D03*
X247389Y262139D03*
X257253Y259197D03*
X257046Y279607D03*
X255205Y272755D03*
X244109Y277996D03*
X247389Y268139D03*
X257253Y271197D03*
Y268197D03*
X250399Y296848D03*
X253611Y293765D03*
X250399Y290548D03*
X244099Y284248D03*
X250399D03*
X244099Y293698D03*
X258380Y295984D03*
X254334Y298728D03*
X247249Y303148D03*
X244118Y309387D03*
X254007Y306819D03*
X244118Y303187D03*
X257057Y309636D03*
X244099Y299998D03*
X247249Y306298D03*
X257418Y303533D03*
X247281Y315727D03*
X247290Y327694D03*
X254631Y324716D03*
X254998Y329779D03*
X256276Y322652D03*
X247789Y322910D03*
X254905Y327213D03*
X248509Y339207D03*
X254819Y332435D03*
X250466Y344381D03*
X245691Y341215D03*
X247218Y333049D03*
X255009Y338318D03*
X246685Y337357D03*
X255124Y335244D03*
X247025Y330512D03*
X251334Y352857D03*
X259444Y354291D03*
X246265Y355855D03*
X251491Y357134D03*
X256588Y359005D03*
X244595Y363535D03*
X250661Y384780D03*
X256532Y384895D03*
X247065Y385398D03*
X244546Y385315D03*
X253762Y385255D03*
X247797Y406029D03*
X250297D03*
X252797D03*
X245297D03*
X244196Y419610D03*
Y417010D03*
Y427610D03*
Y425010D03*
Y433010D03*
Y435610D03*
X254813Y427018D03*
X252670Y443592D03*
X246465Y464893D03*
X251780Y460883D03*
X257568Y461513D03*
X255509Y472253D03*
X246109Y472465D03*
X251309Y472553D03*
X245609Y517182D03*
X252036Y582131D03*
X245860Y575049D03*
X249909Y568653D03*
X259678Y581553D03*
X249541Y587156D03*
X253709Y586128D03*
X249541Y583156D03*
X253187Y596382D03*
X246639Y608378D03*
Y605778D03*
X249640Y602519D03*
X246639Y624378D03*
Y621778D03*
Y616378D03*
Y613778D03*
X249013Y628514D03*
X251803Y636704D03*
X254773Y644424D03*
X254303Y636744D03*
X256463Y639364D03*
X252173Y644344D03*
X249083Y636664D03*
X256513Y642494D03*
X246553Y636684D03*
X249462Y648383D03*
X257271Y671772D03*
X252486D03*
X253398Y692357D03*
X244780Y682521D03*
X250795Y703150D03*
X251451Y697465D03*
X259170Y705138D03*
X254940Y712381D03*
X258570Y722981D03*
X255310Y715915D03*
X248530Y721829D03*
X250630Y719457D03*
X253340Y724726D03*
X248440Y736163D03*
X257440Y736041D03*
X252940Y736318D03*
X248770Y724631D03*
X252940Y733567D03*
X256650Y778342D03*
X247900Y778823D03*
X252470Y785797D03*
X252028Y791695D03*
X262955Y12663D03*
X266111Y29229D03*
X265789Y20990D03*
X268809Y16400D03*
X274990Y16396D03*
X268372Y40782D03*
X265872D03*
X272010Y40553D03*
X274510D03*
X273873Y63167D03*
X269793D03*
X261750Y75886D03*
X267703Y89397D03*
X272245Y89585D03*
X263703Y93847D03*
X271133Y92787D03*
X265830Y102566D03*
X264210Y96914D03*
X273973Y97645D03*
X262473Y106937D03*
X263683Y99902D03*
X269010Y121648D03*
X264980Y121886D03*
X269620Y243240D03*
X269192Y248209D03*
X272242Y244842D03*
X272620Y238653D03*
X260108Y240376D03*
X267118Y245587D03*
X271458Y241347D03*
X270260Y237037D03*
X266187Y249852D03*
X267020Y257079D03*
X263029Y259139D03*
X265073Y266697D03*
X263029Y265139D03*
X271811Y256687D03*
X271898Y263173D03*
X273521Y265849D03*
X260068Y262187D03*
X263268Y262370D03*
X263774Y256464D03*
X272464Y259964D03*
X269263Y252800D03*
X271944Y278363D03*
X264386Y280407D03*
X265944Y278363D03*
X274886Y272587D03*
X273386Y280407D03*
X270444Y270543D03*
X271886Y272587D03*
X265886Y271718D03*
X268886Y272587D03*
X268944Y278363D03*
X263029Y271139D03*
Y268139D03*
X273444Y270543D03*
X274944Y278363D03*
X270386Y280407D03*
X267386D03*
X262886Y288227D03*
X264386Y296047D03*
X267386D03*
X261463Y296111D03*
X265825Y293987D03*
X268867Y293942D03*
X270444Y286183D03*
X265768Y287546D03*
X273444Y286183D03*
X273618Y295387D03*
X271811Y303313D03*
X271944Y309643D03*
X262944D03*
X261386Y311687D03*
X260045Y309615D03*
X268944Y309643D03*
X265944Y309640D03*
X261915Y302033D03*
X269380Y302736D03*
X264501Y303109D03*
X266939Y303281D03*
X274303Y303413D03*
X259820Y303800D03*
X274832Y309687D03*
X262035Y322679D03*
X267883Y325837D03*
X265318Y326487D03*
X270525Y325754D03*
X262201Y328491D03*
X272967Y325842D03*
X275517D03*
X267030Y330147D03*
X262700Y325494D03*
X268502Y344181D03*
X263576Y340898D03*
X274701Y333804D03*
X270326Y335795D03*
X270485Y339030D03*
X264015Y336151D03*
X263173Y331794D03*
X267943Y339617D03*
X270293Y330540D03*
X272964Y330669D03*
X262379Y338103D03*
X262247Y334502D03*
X270071Y333021D03*
X272263Y334222D03*
X272352Y340900D03*
X269456Y355353D03*
X269117Y352876D03*
X269886Y358753D03*
X260536Y374216D03*
X270293Y363972D03*
X273477Y385100D03*
X261663Y385193D03*
X267993Y390695D03*
X270796Y386643D03*
X266882Y388165D03*
X261539Y387755D03*
X264421Y384812D03*
X275497Y390758D03*
X263419Y393450D03*
X265162Y401391D03*
X272220Y401343D03*
X262798Y417886D03*
X271720Y422587D03*
X265532Y422648D03*
X269630Y424884D03*
X274180Y424966D03*
X266822Y443297D03*
X275256Y445753D03*
X271035Y443051D03*
X273735Y443034D03*
X273509Y471649D03*
X263807Y461234D03*
X260609Y472453D03*
X264909Y472553D03*
X269109Y472353D03*
X275452Y483219D03*
X267741Y491608D03*
X263924Y491754D03*
X269609Y576413D03*
X274309Y574653D03*
X261175Y569054D03*
X263792Y574203D03*
X268009Y570953D03*
X273480Y589201D03*
X269609Y588653D03*
X266610Y654171D03*
X270040Y651241D03*
X269640Y655290D03*
X270430Y665576D03*
X269709Y672575D03*
X265913Y671772D03*
X261890Y664761D03*
X265550Y668415D03*
X274360Y673831D03*
X270140Y691038D03*
X272460Y687889D03*
X267240Y682519D03*
X269420Y677062D03*
X265300Y702131D03*
X272650Y693742D03*
X269410Y706003D03*
X267124Y707892D03*
X273510Y699749D03*
X266170Y694826D03*
X260680Y712988D03*
X271210Y718000D03*
X264600Y723086D03*
X270940Y722080D03*
X275440Y735626D03*
X261940Y735878D03*
X266440Y736030D03*
X270940Y735642D03*
X263430Y770417D03*
X264340Y778780D03*
X272175Y783074D03*
X271713Y788695D03*
Y791695D03*
X259902D03*
X278660Y10073D03*
X284505Y30676D03*
X287766Y21289D03*
X287476Y37125D03*
X290823Y63167D03*
X282023D03*
X277853D03*
X277000Y88323D03*
X286263Y88677D03*
X276603Y92119D03*
X287423Y91857D03*
X287595Y106109D03*
X279010Y104889D03*
X286710Y95717D03*
X281200Y98369D03*
X289720Y96094D03*
X278760Y101061D03*
X278354Y244281D03*
X290154Y244007D03*
X285934Y243931D03*
X282178Y244005D03*
X279161Y237817D03*
X289254Y255688D03*
X286492Y258364D03*
X283660Y251542D03*
X281954Y255588D03*
X288954Y260788D03*
X276328Y264687D03*
X276904Y252550D03*
X282166Y262922D03*
X281945Y260231D03*
X278811Y259135D03*
X279336Y264795D03*
X277886Y272587D03*
X280886D03*
X286010Y276042D03*
X282867Y281142D03*
X276444Y270543D03*
X282309Y270435D03*
X279444Y270543D03*
X277944Y278363D03*
X279386Y280407D03*
X276386D03*
X281767Y277742D03*
X276507Y295816D03*
X290363Y286082D03*
X286132Y285953D03*
X281818Y290787D03*
X278918Y286887D03*
X276444Y286183D03*
X279386Y311687D03*
X285890Y311357D03*
X277020Y302298D03*
X282337Y308217D03*
X281859Y310862D03*
X277816Y309678D03*
X279754Y303269D03*
X281461Y321744D03*
X280776Y326412D03*
X286071Y329184D03*
X278067Y325842D03*
X282167Y324242D03*
X288466Y325343D03*
X285704Y321809D03*
X275660Y338857D03*
X281212Y338079D03*
X277288Y334282D03*
X282234Y333792D03*
X285794Y339063D03*
X281205Y340997D03*
X279718Y333694D03*
X275602Y343811D03*
X289191Y341348D03*
X290190Y352480D03*
X278943Y346914D03*
X277718Y352687D03*
X282818D03*
X286711Y352668D03*
X283140Y346082D03*
X286020Y356454D03*
X277040Y376172D03*
X279863Y367513D03*
X286550Y374402D03*
X281450Y373151D03*
X276687Y385100D03*
X288687Y385290D03*
X281864Y386178D03*
X284687Y386769D03*
X285390Y390550D03*
X288220Y389630D03*
X283820Y396266D03*
X281142Y402379D03*
X287067Y402358D03*
X276400Y422341D03*
X280010Y422279D03*
X281190Y424966D03*
X278080Y424760D03*
X286210Y444926D03*
X289630Y444828D03*
X283212Y442286D03*
X286100Y442298D03*
X288742Y442090D03*
X287970Y446705D03*
X282000Y444966D03*
X279112Y444954D03*
X276626Y442913D03*
X279990Y442071D03*
X276809Y471853D03*
X276347Y459741D03*
X280210Y460762D03*
X287567Y470649D03*
Y467649D03*
X280380Y467284D03*
X278990Y464793D03*
X284332Y472834D03*
X282298Y483803D03*
X277470Y481197D03*
X280970D03*
X288009Y495653D03*
X284024Y502595D03*
X290323D03*
X287174Y543541D03*
X290323D03*
Y565589D03*
Y559289D03*
Y562439D03*
X277725Y552989D03*
X284024Y556139D03*
X280874D03*
X279658Y574443D03*
X285530Y573002D03*
X291066Y590488D03*
Y593088D03*
X283650Y589044D03*
X278109Y589238D03*
X287997Y649064D03*
X280880Y650295D03*
X278699Y656491D03*
X289171Y661908D03*
X279090Y668504D03*
X279785Y663876D03*
X289365Y665845D03*
Y673719D03*
X279843Y675688D03*
X288880Y689467D03*
X278350Y687309D03*
X275710Y681593D03*
X289248Y680521D03*
X275560Y697804D03*
X279060Y693306D03*
X284760Y707022D03*
X286798Y704143D03*
X278370Y705093D03*
X277475Y695723D03*
X278341Y717269D03*
X289060Y722193D03*
X281830Y722184D03*
X285130Y714433D03*
X275880Y722141D03*
X285880Y722268D03*
X289150Y718548D03*
X279940Y724126D03*
X289240Y724687D03*
X283990Y734977D03*
X280210Y734805D03*
X288390Y734796D03*
X284020Y724956D03*
X284532Y747493D03*
X275627Y777692D03*
X281930Y773190D03*
X286722Y785929D03*
X279587Y791695D03*
X295307Y41260D03*
X295390Y44017D03*
X295610Y50299D03*
X295560Y52907D03*
X294903Y63167D03*
X306693D03*
X303053D03*
X298883D03*
X296093Y88477D03*
X302853Y89057D03*
X301870Y92072D03*
X296870D03*
X294800Y100593D03*
X295490Y97209D03*
X302370Y95215D03*
X291927Y102991D03*
X293505Y94965D03*
X296927Y102991D03*
X303220Y98397D03*
X293873Y130357D03*
X302930Y132994D03*
X300118Y250987D03*
X296176Y249585D03*
X299776Y248010D03*
X295910Y266706D03*
X295110Y262961D03*
X301511Y262204D03*
X300477Y265010D03*
X296210Y253187D03*
X300310Y253842D03*
Y257242D03*
X292710Y266542D03*
X295307Y275439D03*
X294510Y280709D03*
X301473Y282650D03*
X297810Y280709D03*
X301723Y279150D03*
X297782Y291966D03*
X295010Y286767D03*
X301182Y291966D03*
X294382D03*
X305132Y286867D03*
X298332D03*
X301732D03*
X297668Y300709D03*
X294888Y304456D03*
X294781Y309788D03*
X301795Y310398D03*
X296639Y308057D03*
X305250Y310342D03*
X300201Y300874D03*
X303197Y304297D03*
X295200Y321473D03*
X294596Y328129D03*
X297073Y329159D03*
X294218Y343587D03*
X294888Y335326D03*
X298452Y340487D03*
X305880Y339046D03*
X306820Y342146D03*
X299410Y331201D03*
X303759Y331478D03*
X294618Y348287D03*
X293467Y352442D03*
X305446Y359450D03*
X295527Y359812D03*
X298202Y374572D03*
X303171Y374224D03*
X291686Y375177D03*
X295388Y375644D03*
X303722Y385367D03*
X293290Y389737D03*
X291382Y385457D03*
X299533Y394056D03*
X291860Y442927D03*
X292170Y445986D03*
X301240Y470885D03*
X291327Y466811D03*
X300040Y459733D03*
X306220Y477125D03*
X303631Y475607D03*
Y472607D03*
X301209Y488853D03*
X303709Y489353D03*
X297370Y498563D03*
X300209Y495853D03*
X305708Y503043D03*
X296913Y514460D03*
X301457Y513837D03*
X293473Y565589D03*
Y562439D03*
X295047Y554565D03*
X304410Y572782D03*
X291357Y586128D03*
X299121Y597542D03*
X306229Y600263D03*
X301796Y603917D03*
X298303Y613184D03*
X305602Y620685D03*
Y618185D03*
X299629Y623877D03*
X299090Y634421D03*
X302870Y633981D03*
X297162Y642065D03*
X293843Y642536D03*
X303110Y639381D03*
X305200Y652883D03*
X301070Y655920D03*
X292850Y656359D03*
X304870Y655747D03*
X306294Y659156D03*
X297394Y657033D03*
X302772Y659604D03*
X301360Y652183D03*
X306294Y667156D03*
Y663156D03*
Y675156D03*
Y671156D03*
X300880Y664296D03*
X294120Y668391D03*
X295890Y662662D03*
X297770Y674720D03*
X305979Y691156D03*
X306145Y683156D03*
X305979Y687156D03*
X306294Y679156D03*
X292970Y682450D03*
X295950Y689520D03*
X293068Y677108D03*
X296858Y702544D03*
X297300Y697221D03*
X301696Y701851D03*
Y699351D03*
X293286Y703504D03*
X305990Y697189D03*
X303681Y714421D03*
X305213Y720393D03*
X293300Y718944D03*
X296885Y718059D03*
X297223Y715523D03*
X291318Y713875D03*
X291790Y735976D03*
X306540Y724266D03*
X297940Y724377D03*
X302660Y736359D03*
X298160Y736489D03*
X302810Y733807D03*
X298590Y733669D03*
X293480Y725080D03*
X295700Y733133D03*
X293440Y748380D03*
X291340Y771217D03*
X295100Y786269D03*
X299249Y771403D03*
X304740Y777277D03*
X291398Y792234D03*
X299272Y791695D03*
X317334Y10955D03*
X322640Y9774D03*
X317334Y28955D03*
X314640Y63167D03*
X310483D03*
X318543D03*
X322713D03*
X314830Y92851D03*
X312183Y88837D03*
X321463Y88517D03*
X315083Y90207D03*
X311553Y92347D03*
X310850Y99620D03*
X320740Y98599D03*
X312223Y96407D03*
X317970Y95961D03*
X311420Y250230D03*
X311290Y247249D03*
X315410Y258656D03*
X312680Y258353D03*
X307204Y304212D03*
X321643Y321928D03*
X309143D03*
X311643D03*
X314143D03*
X316643D03*
X319143D03*
X322765Y327721D03*
X311740Y325839D03*
X322210Y336696D03*
X319323Y338320D03*
X309510Y344127D03*
X313980Y335813D03*
X314550Y331564D03*
X318480Y335039D03*
X321130Y342418D03*
X309190Y336959D03*
X319666Y354376D03*
X319807Y346376D03*
X321150Y357730D03*
X319288Y350376D03*
X307410Y348380D03*
X309131Y374573D03*
X314860Y367656D03*
X313222Y374229D03*
X322255Y371935D03*
X321297Y367739D03*
X319363Y372149D03*
X315383Y387863D03*
X307116Y385979D03*
X315533Y384749D03*
X310484Y383312D03*
X316190Y413299D03*
X317140Y421775D03*
X321910Y410139D03*
X311610Y432528D03*
X313530Y436460D03*
X315940Y438104D03*
X319478Y429389D03*
X308220Y432552D03*
X322599Y432505D03*
X309440Y426404D03*
X318950Y432473D03*
X316963Y467655D03*
X321357Y456709D03*
X307800Y467859D03*
X310380Y473942D03*
X316956Y478833D03*
X321246Y472669D03*
X315980Y472128D03*
X307670Y473605D03*
X320080Y512736D03*
X318968Y536052D03*
X313888Y566003D03*
X313141Y550821D03*
X313075Y553755D03*
X313108Y556556D03*
X313275Y559590D03*
X316788Y572903D03*
X316688Y569603D03*
X313347Y570695D03*
X319135Y591407D03*
X313419Y594040D03*
X313227Y590232D03*
X310919Y594040D03*
X310627Y590232D03*
X315957Y594127D03*
X312641Y611556D03*
X307996Y611536D03*
X312656Y606881D03*
X307994Y606886D03*
X320094Y604114D03*
X320512Y613603D03*
X308102Y620685D03*
Y618185D03*
X320367Y618071D03*
X314910Y627222D03*
X317722Y614646D03*
X308741Y623871D03*
X311311Y618197D03*
X317492Y618193D03*
X307574Y633762D03*
X314940Y642067D03*
X310453Y642451D03*
X320360Y642275D03*
X311382Y635432D03*
X314790Y652049D03*
X317130Y653628D03*
X316184Y662630D03*
X314614Y690767D03*
X316184Y687630D03*
X322440Y700130D03*
X320110Y703093D03*
X316165Y693404D03*
X313230Y702465D03*
X317580Y719996D03*
X307113Y713003D03*
X321820Y712680D03*
X311990Y717601D03*
X319620Y716403D03*
X309531Y714298D03*
X312972Y712693D03*
X318090Y712846D03*
X307940Y736445D03*
X311440Y735831D03*
X315940Y735924D03*
X320440Y736031D03*
X307280Y733705D03*
X321930Y724895D03*
X314930Y724533D03*
X307146Y769416D03*
X315020Y780559D03*
X320657Y779595D03*
X320440Y771967D03*
X311083Y791871D03*
X318957Y791695D03*
X323334Y12377D03*
X323871Y25812D03*
Y16812D03*
Y19812D03*
Y28812D03*
X336316Y31815D03*
X327117Y31840D03*
X326353Y63167D03*
X336024Y88176D03*
X329643Y89887D03*
X335668Y92822D03*
X330668D03*
X325360Y92517D03*
X324070Y88861D03*
X336340Y99265D03*
X327950Y101057D03*
X323000Y94337D03*
X325970Y98817D03*
X327430Y108208D03*
X327190Y103818D03*
X337630Y106304D03*
X334720Y102184D03*
X332453Y122297D03*
X331583Y128717D03*
X336495Y290569D03*
X331376Y299883D03*
X328526Y308696D03*
X334478Y299604D03*
X336720Y310846D03*
X337293Y316660D03*
X333540Y315590D03*
X332700Y333089D03*
X333726Y353801D03*
X333440Y349221D03*
X327058Y358376D03*
X323040Y354485D03*
X334816Y367787D03*
X337316Y367758D03*
X337330Y372679D03*
X334816Y372609D03*
X336850Y380332D03*
X325749Y418701D03*
X331090Y424304D03*
X331900Y419317D03*
X336740Y417069D03*
X324940Y413899D03*
X336218Y424850D03*
X325180Y432577D03*
X336088Y454511D03*
X326190Y448621D03*
X329120Y449203D03*
X327780Y445819D03*
X331360Y447306D03*
X322986Y467109D03*
X325040Y480129D03*
X330115Y490303D03*
X335162Y502791D03*
X326740Y495763D03*
X329672Y502057D03*
X326170Y518386D03*
X335860Y516486D03*
X336010Y531598D03*
X329348Y533403D03*
X332408Y544097D03*
X323154Y556367D03*
Y558867D03*
Y553867D03*
X337550Y558618D03*
Y556118D03*
Y553618D03*
X330388Y565803D03*
X336057Y575657D03*
X332388Y567703D03*
X328088Y567503D03*
X323931Y589733D03*
X329260Y603381D03*
X328930Y611691D03*
X323346Y621930D03*
X329110Y623514D03*
X330440Y639504D03*
X328032Y642674D03*
X337070Y639759D03*
X326350Y638968D03*
X332710Y642694D03*
X328760Y657144D03*
X327540Y653432D03*
X335610Y658177D03*
X332747Y655636D03*
X332190Y659883D03*
X329912Y662383D03*
X335915Y675011D03*
X335390Y667895D03*
X326890Y676159D03*
X327257Y672408D03*
X333180Y665611D03*
X335130Y670744D03*
X334313Y663113D03*
X327500Y667244D03*
X324970Y665128D03*
X337030Y677894D03*
X337798Y686721D03*
X324120Y703114D03*
X336110Y693934D03*
X331520Y701642D03*
X332720Y698170D03*
X325841Y719731D03*
X330410Y712895D03*
X325560Y713391D03*
X336990Y735701D03*
X324940Y736067D03*
X329440Y735814D03*
X333940Y735895D03*
X329590Y724283D03*
X334640Y725035D03*
X338270Y733387D03*
X338460Y724585D03*
X326280Y775980D03*
X337800Y774677D03*
X339162Y9304D03*
Y11904D03*
X350411Y21277D03*
X339239Y24232D03*
X339471Y19373D03*
Y16773D03*
X339239Y26832D03*
X346600Y38561D03*
X346150Y36030D03*
X353060Y61504D03*
X349490Y57698D03*
X352578Y74292D03*
X339750Y73383D03*
X350198Y88277D03*
X343111Y88429D03*
X340543Y88647D03*
X345463Y90837D03*
X353713Y93057D03*
X344770Y101718D03*
X351793Y105404D03*
X344873Y94847D03*
X343070Y99372D03*
X340450Y101914D03*
X344073Y124397D03*
X351533Y124697D03*
X343743Y120967D03*
X351373Y134367D03*
X351503Y130972D03*
Y127972D03*
X345297Y284849D03*
X342955Y291523D03*
X341693Y286010D03*
X354170Y308924D03*
X351500Y301795D03*
X340792Y307107D03*
X353903Y314077D03*
X353841Y306194D03*
X339370Y329176D03*
X341910Y325739D03*
X344720D03*
X339600Y332076D03*
X343880Y356989D03*
X349110Y375767D03*
X352420Y375672D03*
X343430Y385937D03*
X343770Y382166D03*
X351650Y420270D03*
X346862Y424850D03*
X345270Y452745D03*
X346750Y466532D03*
X352890Y479656D03*
X348000Y479150D03*
X352260Y483029D03*
X338762Y479636D03*
X339506Y482841D03*
X348220Y486484D03*
X352160Y502138D03*
X351250Y499752D03*
X348870Y501571D03*
X343420Y497966D03*
X353400Y507260D03*
X353460Y504536D03*
X348190Y511550D03*
X353120Y510003D03*
X350690Y516376D03*
X340902Y503742D03*
X352940Y518025D03*
X341512Y512429D03*
X350902Y512520D03*
X346350Y517286D03*
X340182Y531787D03*
X351110Y531835D03*
X340330Y541931D03*
X342190Y565848D03*
X342759Y599193D03*
X339616Y603438D03*
Y605938D03*
X339384Y611544D03*
X351964Y599332D03*
X339600Y621293D03*
Y618693D03*
X339384Y614144D03*
X353298Y633903D03*
X340340Y638054D03*
X340669Y644827D03*
X348480Y638558D03*
X345580Y638109D03*
X347670Y642285D03*
X351728Y653860D03*
X351722Y659319D03*
X340630Y655093D03*
X351730Y649206D03*
X339930Y661219D03*
X353902Y667128D03*
X351730Y663450D03*
X340530Y675658D03*
X351720Y670018D03*
X338970Y670776D03*
X340870Y665042D03*
X340525Y686600D03*
X353260Y688757D03*
X351810Y706800D03*
X339750Y695271D03*
X339010Y700406D03*
X338926Y697752D03*
X344780Y713349D03*
X352400Y722132D03*
X339300Y716800D03*
X342230Y720936D03*
X341190Y712379D03*
X352010Y713968D03*
X342230Y709384D03*
X343730Y724581D03*
X350180Y735880D03*
X350580Y724427D03*
X345610Y733982D03*
X354060Y734790D03*
X350720Y745722D03*
X344710Y785782D03*
X350450Y784982D03*
X346516Y790294D03*
X363025Y12926D03*
X358285Y21325D03*
X366159Y21822D03*
X361930Y60031D03*
X367300Y60442D03*
X356550Y74767D03*
X365670Y64458D03*
X366733Y88477D03*
X359646Y88174D03*
X362133Y90877D03*
X367776Y91746D03*
X358343Y90948D03*
X360827Y108541D03*
X362300Y98674D03*
X369670Y99845D03*
X361470Y101757D03*
X354943Y104191D03*
X354448Y108092D03*
X367560Y120823D03*
X367350Y123927D03*
X365283Y128125D03*
X354580Y298101D03*
X364220Y296795D03*
X357400Y307608D03*
X365970Y299194D03*
X356835Y313894D03*
X369280Y300916D03*
X367220Y303202D03*
X362660Y316986D03*
X357110Y329210D03*
X359410Y317080D03*
X369040Y316735D03*
X369934Y322946D03*
X359120Y331164D03*
X357040Y332970D03*
X365026Y332478D03*
X362540Y361443D03*
X354690Y377000D03*
X364645Y377065D03*
X360960Y389080D03*
X364880Y384455D03*
X364580Y391273D03*
X366140Y407639D03*
X360350Y395873D03*
X369280Y415600D03*
X355250Y420679D03*
X365850Y414874D03*
X368660Y449478D03*
X369500Y445873D03*
X354565Y451562D03*
X354750Y445325D03*
X369507Y464391D03*
X355150Y486758D03*
X368787Y472998D03*
X368943Y506356D03*
X366426Y527722D03*
Y530222D03*
Y532722D03*
X368238Y522673D03*
X358182Y531231D03*
X365329Y546121D03*
X368694Y546159D03*
X368825Y539776D03*
X369918Y592253D03*
X369848Y588903D03*
X360647Y602636D03*
X354973Y605588D03*
Y602588D03*
Y611588D03*
X361473Y620588D03*
X354973Y614588D03*
Y620588D03*
Y623588D03*
X361562Y645175D03*
X363530Y629727D03*
X367858Y657573D03*
X365070Y658065D03*
X365990Y645272D03*
X367870Y650239D03*
X364980Y655266D03*
X363340Y650512D03*
X361650Y658537D03*
X361580Y652755D03*
X362173Y665128D03*
X368200Y672132D03*
X368100Y668133D03*
X361810Y675011D03*
X365620Y663069D03*
X361660Y671306D03*
X365380Y668972D03*
X365160Y672922D03*
X361760Y668716D03*
X367399Y684652D03*
X367866Y677326D03*
X361646Y689228D03*
X367066Y681094D03*
X364320Y680434D03*
X367496Y690248D03*
X361510Y680886D03*
X362040Y684875D03*
X364649Y684022D03*
X364765Y687963D03*
X365090Y676923D03*
X364844Y698332D03*
X361786Y699128D03*
X361717Y695128D03*
X367480Y705169D03*
X367614Y693053D03*
X361580Y703860D03*
X363590Y702324D03*
X364115Y692990D03*
X367520Y701710D03*
X366510Y723622D03*
X361350Y720720D03*
X361490Y712505D03*
X367350Y713661D03*
X357830Y718682D03*
X363162Y739537D03*
X366430Y731459D03*
X357096Y732976D03*
X360246Y730819D03*
X354520Y728701D03*
X363460Y735388D03*
X364750Y727821D03*
X363359Y743537D03*
X364090Y748565D03*
X354420Y749198D03*
X357610Y748302D03*
X366860Y739956D03*
X354870Y771388D03*
X360160Y775523D03*
X363300Y781303D03*
X367904Y778327D03*
X366201Y787976D03*
X354390Y790294D03*
X366201Y790976D03*
X379940Y17789D03*
X382990Y17519D03*
X371180Y17789D03*
X370960Y20577D03*
X381907Y21507D03*
X383280Y59940D03*
X376006Y60991D03*
X383247Y64141D03*
X373560Y63973D03*
X380906Y88134D03*
X373820Y88400D03*
X372776Y91746D03*
X384450Y108830D03*
X372620Y98355D03*
X384090Y98743D03*
X379160Y102923D03*
X374030Y95000D03*
X382087Y103647D03*
X380483Y99047D03*
X378733Y105987D03*
X384863Y95437D03*
X376100Y108780D03*
X376723Y94178D03*
X377363Y121108D03*
X378183Y124904D03*
X374040Y304980D03*
X373640Y301078D03*
X370460Y305908D03*
X371090Y303487D03*
X384248Y319157D03*
X372080Y330574D03*
X379560Y374955D03*
X379720Y372257D03*
X378830Y386352D03*
X382620Y391882D03*
X379300Y380862D03*
X379286Y378015D03*
X379750Y383965D03*
X382190Y388077D03*
X376600Y408045D03*
X382680Y408202D03*
X374560Y412421D03*
X371260Y412879D03*
X376150Y430405D03*
X383750Y437058D03*
X372320Y439514D03*
X371950Y430527D03*
X378910Y430874D03*
X371080Y448276D03*
X372710Y445705D03*
X375190Y463996D03*
X381239Y467171D03*
X371080Y481589D03*
X374203Y482079D03*
X377284Y473374D03*
X374207Y479329D03*
X373850Y496585D03*
X381760Y496004D03*
X374203Y491029D03*
X376540Y498385D03*
X379177Y509798D03*
X383924Y514797D03*
X385040Y521754D03*
X384588Y526069D03*
X382632Y530322D03*
Y527822D03*
Y532822D03*
X373538Y520213D03*
X376528Y520138D03*
X379733Y549392D03*
X370309Y550322D03*
X377150Y543151D03*
X376490Y540574D03*
X382596Y537379D03*
X382333Y540414D03*
X384485Y552365D03*
X382595Y554166D03*
X385410Y566122D03*
X383344Y590662D03*
Y593262D03*
X373448Y589053D03*
X373518Y592403D03*
X385573Y629998D03*
X371407Y641507D03*
X373218Y634217D03*
X382580Y637413D03*
X380101Y660239D03*
X379093Y657739D03*
X376650Y654157D03*
X379492Y650239D03*
X376089Y646156D03*
X373680Y662417D03*
X376087Y670156D03*
X377211Y673197D03*
X379461Y675246D03*
X379462Y666156D03*
X379791Y679454D03*
X376946Y689985D03*
X377681Y694244D03*
X377679Y701168D03*
X377669Y706237D03*
X377100Y697218D03*
X371170Y711574D03*
X382960Y711431D03*
X372110Y720308D03*
X376190Y711259D03*
X375575Y739459D03*
X375548Y731459D03*
X375834Y727459D03*
X377840Y724388D03*
X376770Y734898D03*
X370430Y749138D03*
X373500Y748457D03*
X376960Y788580D03*
Y791580D03*
X399002Y17519D03*
X392600Y20548D03*
X389240D03*
X397655Y21336D03*
X392250Y59899D03*
X389690Y60665D03*
X401310Y61439D03*
X397790Y61360D03*
X393371Y72919D03*
X397790Y69610D03*
X390355Y75775D03*
X401220Y65155D03*
X399804Y88778D03*
X397442Y90667D03*
X389400Y89232D03*
X392493Y92647D03*
X399653Y108357D03*
X391536Y108990D03*
X398820Y95823D03*
X391190Y104173D03*
X388860Y98010D03*
X400163Y99177D03*
X391310Y99570D03*
X399613Y104657D03*
X391233Y96093D03*
X399150Y131773D03*
X391880Y131692D03*
X398088Y128455D03*
X393088D03*
X399858Y249711D03*
X399298Y257231D03*
X391998Y258251D03*
X399598Y260251D03*
X398258Y252341D03*
X394378Y260501D03*
X392668Y272511D03*
X399608Y275211D03*
X393458Y282931D03*
X392508Y275581D03*
X400928Y293151D03*
X396098Y283931D03*
X398038Y292571D03*
X399880Y319568D03*
X390080Y331575D03*
X389740Y404725D03*
X395740Y407528D03*
X393370Y411618D03*
X399060Y454322D03*
X399050Y450968D03*
X398800Y462248D03*
Y458058D03*
X392076Y470970D03*
X387080Y486400D03*
X385940Y482478D03*
X388890Y480439D03*
X386410Y477576D03*
X389670Y477262D03*
X389107Y492097D03*
X388982Y496939D03*
X395690Y512774D03*
X396350Y532016D03*
X396558Y522251D03*
X396470Y527847D03*
X396048Y540127D03*
X395922Y536127D03*
X396590Y549310D03*
X399590Y553502D03*
X390000Y567345D03*
X396520Y567444D03*
X393596Y567630D03*
X391630Y597900D03*
X391447Y611973D03*
X394389Y604053D03*
X401353Y624007D03*
X399223Y644930D03*
X394380Y643389D03*
X396940Y658078D03*
X396366Y653229D03*
X399363Y653588D03*
X389856Y645705D03*
X396478Y661529D03*
X399911Y661325D03*
X386173Y665065D03*
X391938Y672320D03*
X392097Y676231D03*
X399873Y666411D03*
X400267Y684029D03*
X390000Y689724D03*
X389961Y682218D03*
X396550Y680266D03*
X399829Y690191D03*
X400968Y686699D03*
X400408Y681193D03*
X390660Y686923D03*
X391910Y696742D03*
X392080Y692796D03*
X391740Y705957D03*
X398620Y701411D03*
X390950Y701922D03*
X389350Y711288D03*
X396150Y708926D03*
X400730Y721954D03*
X394840Y711437D03*
X414949Y75291D03*
X403739Y72783D03*
X404310Y65213D03*
X410713Y76187D03*
X401670Y93807D03*
X404528Y88702D03*
X409060Y92095D03*
X404813Y93887D03*
X407303Y95117D03*
X408072Y109146D03*
X405688Y253581D03*
X404738Y260421D03*
X402948Y253251D03*
X405038Y267521D03*
X401728Y277251D03*
X401618Y267351D03*
X403148Y270191D03*
X405248Y272731D03*
X405878Y294071D03*
X403628Y292201D03*
X408790Y317049D03*
X411240Y316482D03*
X403130Y418091D03*
X406200Y417755D03*
X405980Y414630D03*
X405930Y411386D03*
X406140Y424766D03*
X406150Y433203D03*
X406530Y440667D03*
X406000Y444755D03*
X402900Y444842D03*
X406352Y471405D03*
X409054Y483084D03*
X412260Y482881D03*
X410607Y485620D03*
X413607D03*
X413733Y490781D03*
X410733D03*
X407733D03*
Y493781D03*
Y496781D03*
Y499781D03*
X410733Y493781D03*
X413733D03*
X410733Y496781D03*
X413733D03*
X410733Y499781D03*
X413733D03*
X409985Y508431D03*
X413138Y504813D03*
X413222Y508054D03*
X411439Y516956D03*
X407865Y516627D03*
X405348Y506316D03*
X402458Y505903D03*
X401556Y508937D03*
X407776Y527426D03*
X405954Y532502D03*
X404336Y545280D03*
X408486Y537333D03*
X416515Y547602D03*
X402499Y554143D03*
X404578Y551838D03*
X408736Y551529D03*
X413342Y556219D03*
X410522Y593947D03*
X413022D03*
X412783Y605500D03*
X416454Y621319D03*
X413105Y613739D03*
X403904Y618333D03*
X410085Y618329D03*
X413930Y639810D03*
X403970Y642364D03*
X406100Y631851D03*
X410989Y652957D03*
X413535Y646804D03*
X411982Y660285D03*
X413718Y655267D03*
X410918Y649363D03*
X413966Y675624D03*
X415218Y664203D03*
X411675Y672654D03*
X411065Y667516D03*
X414183Y686151D03*
X411862Y688027D03*
X413643Y680004D03*
X412250Y683196D03*
X411149Y678387D03*
X415834Y693272D03*
X412878Y693183D03*
X414550Y707464D03*
X414318Y700979D03*
X414810Y696968D03*
X409581Y711643D03*
X402540Y710649D03*
X412080Y719034D03*
X414080Y721334D03*
X415730Y710897D03*
X406720Y723395D03*
X413940Y735665D03*
X409010Y726147D03*
X415780Y747078D03*
X421893Y123537D03*
X421473Y160556D03*
Y157556D03*
X421640Y228403D03*
Y223403D03*
X422698Y244301D03*
X422288Y250661D03*
X419038Y242611D03*
X428405Y245194D03*
X424961Y241203D03*
X418905Y245694D03*
X426992Y250016D03*
X427768Y253569D03*
X422178Y266891D03*
X428208Y262109D03*
X422528Y253531D03*
X426335Y267062D03*
X418575Y263691D03*
X420858Y261331D03*
X427817Y258829D03*
X418597Y273538D03*
X418698Y279631D03*
X426948Y281051D03*
X421728Y279141D03*
X428748Y275222D03*
X418998Y289871D03*
X422918Y289501D03*
X418588Y286681D03*
X421128Y292601D03*
X423178Y284601D03*
X427909Y286759D03*
X427468Y292287D03*
X418718Y301181D03*
X428747Y463314D03*
Y468770D03*
X419071Y509283D03*
X431280Y514223D03*
X431356Y516836D03*
X422050Y517028D03*
X425999Y516211D03*
X424873Y513921D03*
X423278Y525160D03*
X428874Y525193D03*
X417520Y525128D03*
X428874Y530627D03*
X417520Y531177D03*
X428745Y536999D03*
X423332Y536763D03*
X417617Y536773D03*
X428039Y548119D03*
X421461Y547703D03*
X420883Y556729D03*
X428039Y556539D03*
X423861Y556535D03*
X431145Y556608D03*
X424904Y586283D03*
X429340Y596874D03*
X431520Y607039D03*
X422221Y619873D03*
X422470Y647852D03*
X432180Y647458D03*
X425334Y656419D03*
X422007Y652732D03*
X423623Y645396D03*
X422026Y656883D03*
X429820Y656709D03*
X425146Y672426D03*
X430140Y665660D03*
X417974Y663446D03*
X421080Y665945D03*
X422222Y675226D03*
X426100Y667884D03*
X422510Y677836D03*
X430873Y684536D03*
X425173Y688588D03*
X427900Y679709D03*
X430861Y679156D03*
X422981Y690351D03*
X430862Y691156D03*
X430813Y687156D03*
X427210Y691934D03*
X423317Y705344D03*
X423055Y696713D03*
X430618Y699156D03*
X430667Y703156D03*
X430731Y707156D03*
X430813Y695156D03*
X427230Y707377D03*
X426391Y701173D03*
X423242Y707949D03*
X425590Y695895D03*
X421350Y694003D03*
X422940Y723802D03*
X430738Y711156D03*
X427130Y717871D03*
X421730Y717398D03*
X429240Y721014D03*
X424410Y718429D03*
X417330Y717420D03*
X431440Y723955D03*
X420160Y724309D03*
X430940Y735895D03*
X426430Y735126D03*
X418440Y735930D03*
X420290Y733741D03*
X423900Y736055D03*
X424200Y733399D03*
X426440Y724240D03*
X421690Y779548D03*
X417880Y786361D03*
X428250Y772054D03*
X426900Y779752D03*
X421321Y791476D03*
X417384D03*
X446268Y69074D03*
X442380Y75513D03*
X439670Y70044D03*
X446088Y90159D03*
Y85159D03*
Y87659D03*
X446920Y78358D03*
X447715Y97926D03*
X434158Y122272D03*
X443448Y124552D03*
X441518Y122242D03*
X434158Y125092D03*
X444828Y122132D03*
X446522Y146932D03*
X433253Y160737D03*
X433363Y157607D03*
X444550Y184057D03*
X442520Y223623D03*
X442580Y236459D03*
X441580Y250730D03*
X443212Y240957D03*
X447900Y265292D03*
X441498Y266731D03*
X441792Y259473D03*
X442148Y279361D03*
X442165Y271284D03*
X441076Y294906D03*
X445540Y288853D03*
X445890Y283317D03*
X441361Y300812D03*
X438340Y403375D03*
X439150Y400930D03*
X443240Y401984D03*
X446830Y400551D03*
X445900Y403460D03*
X437887Y471073D03*
X444920Y485259D03*
X447770Y485290D03*
X437716Y476295D03*
X445366Y490657D03*
X445199Y494590D03*
X439749Y506523D03*
X439762Y515540D03*
Y523757D03*
X447781Y523888D03*
X434605Y521488D03*
X442763Y549595D03*
X445838Y538085D03*
X435998Y539726D03*
X434203Y542897D03*
X438722Y538842D03*
X441063Y540563D03*
X448329Y534995D03*
X441326Y556050D03*
X437832Y556374D03*
X434187Y556444D03*
X442240Y553337D03*
X437516Y587579D03*
X441230Y587341D03*
X447830Y588739D03*
X446378Y582681D03*
X435319Y600123D03*
X437120Y612933D03*
X440135Y615808D03*
X448460Y625960D03*
X445604Y629045D03*
X433872Y645119D03*
X446980Y638774D03*
X437100Y643793D03*
X446500Y645075D03*
X443850Y634754D03*
X434681Y642639D03*
X435420Y647117D03*
X437509Y648996D03*
X446799Y657526D03*
X435972Y655595D03*
X444700Y651900D03*
X445270Y660832D03*
X444403Y665963D03*
X447210Y665143D03*
X436000Y675706D03*
X435539Y671628D03*
X436445Y667628D03*
X447161Y673564D03*
X444458Y669350D03*
X440688Y684438D03*
Y689438D03*
X440690Y702386D03*
X440688Y694438D03*
X446900Y714648D03*
X442650Y719485D03*
X446260Y722014D03*
X444530Y723917D03*
X440660Y712065D03*
X439200Y722093D03*
X447240Y724780D03*
X439940Y735507D03*
X443940Y735681D03*
X435440Y735928D03*
X436440Y724710D03*
X442120Y724781D03*
X447680Y733564D03*
X444370Y770152D03*
X434540Y778500D03*
X441006Y785297D03*
Y791476D03*
X437069D03*
X458120Y44721D03*
X464170Y56436D03*
X450618Y69004D03*
X457583Y66384D03*
X454263Y77675D03*
X462294Y87759D03*
Y85259D03*
Y90259D03*
X450917Y97566D03*
X461594Y99342D03*
X449538Y105144D03*
X453168D03*
X453940Y98586D03*
X460412Y105704D03*
X457912D03*
X462912D03*
X453298Y122254D03*
X450798D03*
X452158Y124582D03*
X458818Y122065D03*
Y125422D03*
X461880Y150596D03*
X455292Y162797D03*
X455470Y166963D03*
X452669Y157140D03*
X455913Y178698D03*
X454763Y183503D03*
X453340Y185670D03*
X457482Y183523D03*
X462790Y183489D03*
X452115Y195057D03*
X459000Y200500D03*
X450650Y203785D03*
X450576Y234431D03*
X454150Y249053D03*
X453620Y245162D03*
X457165Y262368D03*
X456800Y259233D03*
X459108Y253181D03*
X449860Y267121D03*
X456530Y256034D03*
X449290Y276227D03*
X449860Y272121D03*
X452900Y281647D03*
X453780Y292411D03*
X453810Y289325D03*
X451790Y300129D03*
X461130Y408318D03*
X448970Y403846D03*
X451950Y402434D03*
X461080Y411451D03*
X463690Y451813D03*
X461590Y446700D03*
X461540Y449833D03*
X457702Y475480D03*
X460702D03*
X454702D03*
X463702D03*
X450899Y483452D03*
X463540Y495717D03*
X457537Y495546D03*
X454770Y495587D03*
X450813Y492993D03*
X463565Y515723D03*
X452895Y510061D03*
X449402Y515514D03*
X451504Y529734D03*
X450540Y521331D03*
X463991Y531504D03*
X451325Y525981D03*
X456722Y529536D03*
X454022Y541052D03*
X463031Y543563D03*
X453917Y550069D03*
X450367Y540720D03*
X453700Y545047D03*
X453854Y555069D03*
X460236Y581679D03*
X455890Y592792D03*
X450778Y583106D03*
X458600Y599200D03*
X453775Y600614D03*
X462270Y612911D03*
X453935Y624739D03*
X459690Y626423D03*
X464050Y633877D03*
X458903Y644884D03*
X456342Y649436D03*
X461997Y654507D03*
X463178Y647483D03*
X458650Y666543D03*
X460587Y669424D03*
X457138Y663251D03*
X463020Y661023D03*
X464330Y663251D03*
X458820Y674137D03*
X463120Y681992D03*
X460530Y681874D03*
X459650Y685993D03*
X457730Y682010D03*
X456960Y685581D03*
X461960Y684394D03*
X459950Y722720D03*
X453960Y723142D03*
X449060Y721761D03*
X457060Y722427D03*
X460822Y712620D03*
X451820Y712210D03*
X454070Y714226D03*
X453530Y736212D03*
X458050Y725053D03*
X462440Y735687D03*
X455410Y734113D03*
X450410Y733682D03*
X451320Y725044D03*
X461565Y785806D03*
X463750Y780452D03*
X454120Y785923D03*
X460691Y791476D03*
X456754D03*
X475310Y59746D03*
X464767Y78145D03*
X475030Y63879D03*
X479450Y63721D03*
X466647Y91224D03*
X466682Y102410D03*
X474381Y125310D03*
X478088Y125219D03*
X471500Y138000D03*
X473200Y140300D03*
X468400Y135800D03*
X470324Y133424D03*
X474813Y162220D03*
X467473Y159766D03*
X473951Y157235D03*
X473950Y172124D03*
X475760Y168747D03*
X472670Y166398D03*
X473580Y177859D03*
X474630Y174843D03*
X480220Y185766D03*
X475770Y186451D03*
X468452Y197934D03*
X471300Y201900D03*
X476400Y203100D03*
X478000Y212500D03*
X466200Y207300D03*
X464810Y311253D03*
X470090Y332824D03*
X475190Y339013D03*
X474140Y408318D03*
X469590D03*
X465330D03*
X468210Y401505D03*
X465913Y402659D03*
X465883Y399834D03*
X474080Y411451D03*
X469530D03*
X465270D03*
X480050Y419556D03*
X471540Y437214D03*
X473140Y439971D03*
X469500Y447730D03*
X467920Y451667D03*
X472210Y450267D03*
X465730Y449833D03*
X465790Y446700D03*
X479575Y467597D03*
X479754Y462988D03*
X466702Y475480D03*
X480118Y479107D03*
Y474107D03*
X466307Y495676D03*
X467677Y510055D03*
X467496Y513179D03*
X466587Y515764D03*
X467586Y506807D03*
X474130Y553659D03*
X474290Y563565D03*
X471804Y561085D03*
Y556085D03*
X471190Y593964D03*
X468740Y585897D03*
X469890Y596580D03*
X473153Y622451D03*
X476320Y629280D03*
X465580Y641417D03*
X469229Y638135D03*
X475820Y635422D03*
X478905Y659426D03*
X470190Y648693D03*
X474946Y659376D03*
X468810Y652180D03*
X479512Y649436D03*
X468540Y655799D03*
X479353Y668666D03*
X466049Y675327D03*
X466980Y667059D03*
X469977Y676496D03*
X468260Y664366D03*
X469467Y679915D03*
X479409Y682305D03*
X479354Y677054D03*
X477710Y722299D03*
X466620Y714137D03*
X473940Y714184D03*
X471450Y736368D03*
X466440Y735987D03*
X471310Y733811D03*
X466440Y724465D03*
X470550Y724034D03*
X473560Y724951D03*
X465850Y733428D03*
X476980Y736594D03*
X476160Y734205D03*
X474940Y747192D03*
X471780Y786300D03*
X476439Y791476D03*
X486810Y60785D03*
X483240Y60546D03*
X487030Y68075D03*
X488438Y109623D03*
Y100123D03*
X484068Y99980D03*
X492955Y99440D03*
X494355Y108674D03*
X491875Y125222D03*
X487140Y123397D03*
X484350Y112811D03*
X487020Y119754D03*
X494910Y133316D03*
X487857Y152147D03*
X490760Y154771D03*
X488570Y147486D03*
X492424Y142234D03*
X494467Y148867D03*
X487740Y161235D03*
X488220Y157515D03*
X490130Y163086D03*
X493670Y171871D03*
X489040Y169483D03*
X482500Y184169D03*
X487080Y180918D03*
X482980Y181071D03*
X488850Y175419D03*
X494210Y175035D03*
X495300Y201600D03*
X487839Y194142D03*
X487464Y198566D03*
X488017Y203716D03*
X486370Y189279D03*
X491046Y207506D03*
X486738Y210434D03*
X487168Y214568D03*
X491320Y231809D03*
X492700Y223800D03*
X488816Y242877D03*
X484169Y272867D03*
X484780Y314090D03*
X494850Y315733D03*
X480830Y333921D03*
X495140Y385762D03*
X486300Y422150D03*
X481300D03*
X486670Y426196D03*
X495500Y447465D03*
X482880Y467935D03*
Y462935D03*
X483685Y473522D03*
X483641Y479628D03*
X492260Y482826D03*
X494980Y482979D03*
X490334Y497342D03*
X486640Y543687D03*
X485510Y536673D03*
X483209Y545250D03*
Y550250D03*
X490661Y547148D03*
X489962Y540849D03*
X489938Y563425D03*
X486720Y563730D03*
X481380Y553210D03*
X483838Y566194D03*
Y556148D03*
Y561148D03*
X490658Y579025D03*
X487398Y576665D03*
X490693Y570770D03*
X490538Y567825D03*
X481410Y573563D03*
X483838Y571194D03*
X485890Y590563D03*
X489380Y590839D03*
X485380Y596505D03*
X485738Y587125D03*
X490738D03*
X481340Y593296D03*
X494238Y600441D03*
X490600Y608136D03*
X489800Y600200D03*
X487832Y624429D03*
X490040Y622140D03*
X491100Y644351D03*
X491380Y639279D03*
X495900Y641804D03*
X480310Y642224D03*
X491930Y654203D03*
X495622Y660178D03*
X492310Y650516D03*
X482180Y646278D03*
X481253Y654837D03*
X493020Y646701D03*
X484700Y660355D03*
X491157Y675604D03*
X482398Y673087D03*
X482544Y668042D03*
X491044Y667604D03*
X491060Y671604D03*
X490120Y662703D03*
X492770Y665090D03*
X491189Y679656D03*
X494323Y687669D03*
X492294Y682347D03*
X483056Y679628D03*
X481227Y685366D03*
X491167Y687507D03*
X481227Y691366D03*
X491067Y699656D03*
X491380Y694656D03*
X490900Y706145D03*
X481227Y696366D03*
X495560Y694781D03*
X488180Y719244D03*
X490890Y714898D03*
X488090Y710545D03*
X496000Y736152D03*
X483180Y736506D03*
X487940Y735681D03*
X491890Y735740D03*
X494850Y733252D03*
X480620Y734244D03*
X480770Y778125D03*
X485870Y776087D03*
X491720Y776713D03*
X495110Y771733D03*
X480376Y791476D03*
X502900Y57670D03*
X500310Y109211D03*
X508904Y124063D03*
X497430Y124024D03*
X504750Y111749D03*
X509691Y112938D03*
X499456Y128666D03*
X509710Y127269D03*
X500215Y136449D03*
X502132Y146686D03*
X502183Y156709D03*
X500963Y162261D03*
X496360Y167221D03*
X501040Y177297D03*
X498940Y179744D03*
X510000Y173500D03*
X502999Y180541D03*
X499154Y194198D03*
X509100Y191900D03*
X505580Y192555D03*
X498875Y217172D03*
X499225Y205296D03*
X506234Y207368D03*
X499075Y235575D03*
X496123Y233500D03*
X504941Y227859D03*
X498867Y227773D03*
X499405Y242877D03*
X507000Y239000D03*
X504160Y255584D03*
X511070Y310719D03*
X509140Y338005D03*
X504897Y390481D03*
X497111Y388567D03*
X502111D03*
X505819Y417473D03*
X510577Y417741D03*
X498238Y417825D03*
X502687Y417453D03*
X499551Y429636D03*
X502494Y436725D03*
X509486Y433829D03*
X497818Y440265D03*
X509464Y450265D03*
X506456Y446928D03*
X505442Y458719D03*
X502938Y463823D03*
X505843Y465018D03*
X498119Y470011D03*
X511070Y493380D03*
X511520Y496255D03*
X505740Y495880D03*
X511230Y499059D03*
X506230D03*
X511560Y513792D03*
X504613Y522050D03*
X498920Y523803D03*
X503958Y529405D03*
X504613Y525200D03*
X501331Y528932D03*
X500138Y543225D03*
X503448Y540235D03*
X505718Y542865D03*
X503338Y549825D03*
Y544825D03*
X500038Y555925D03*
Y550725D03*
X500138Y563025D03*
Y558625D03*
X500338Y566425D03*
X510338Y571325D03*
X500438Y574925D03*
X500419Y578644D03*
X500538Y572025D03*
X500338Y569425D03*
X499868Y585725D03*
X500538Y588525D03*
X505738Y590525D03*
Y600425D03*
X496140Y608883D03*
X504268Y608625D03*
X500098Y608885D03*
X509238Y608515D03*
X508024Y613598D03*
X500538Y600925D03*
X504980Y616425D03*
X508400Y617803D03*
X502080Y622999D03*
X498350Y627580D03*
X505780Y642543D03*
X501120Y633249D03*
X510700Y634300D03*
X496690Y633589D03*
X501940Y644073D03*
X498666Y653012D03*
X504836Y657097D03*
X503680Y659666D03*
X505690Y654419D03*
X508061Y645381D03*
X504295Y649612D03*
X498040Y675306D03*
X498870Y668324D03*
X504114Y670830D03*
X496453Y670876D03*
X501914Y675624D03*
X504241Y665809D03*
X497320Y665216D03*
X506376Y687436D03*
X506470Y683512D03*
X496577Y684553D03*
X505580Y679105D03*
X496277Y678185D03*
X501540Y681970D03*
X506409Y691373D03*
X500710Y706582D03*
X497350Y699767D03*
X506092Y697575D03*
X510608Y717448D03*
X499842Y710582D03*
X499452Y714582D03*
X502890Y736349D03*
X506105Y724132D03*
X498080Y733252D03*
X509855Y724107D03*
X500260Y729094D03*
X501604Y733003D03*
X501890Y746663D03*
X507935Y785704D03*
X511770Y779940D03*
X499270Y776431D03*
X504440Y772548D03*
X500061Y791476D03*
X496124D03*
X513120Y72069D03*
X512878Y108635D03*
X519625Y108543D03*
X526835Y108314D03*
X525570Y124623D03*
X516146Y113121D03*
X522111Y113310D03*
X518248Y137692D03*
X518640Y125539D03*
X518477Y141401D03*
X527349Y152246D03*
X526875Y161838D03*
X518725Y170525D03*
X512600Y178900D03*
X515600Y172800D03*
X521320Y178184D03*
X516100Y178100D03*
X526621Y177079D03*
X512200Y204200D03*
X526443Y194116D03*
X514500Y194300D03*
X525293Y191705D03*
X515231Y191334D03*
X520015Y194584D03*
X523593Y198171D03*
X512200Y196000D03*
X511997Y207730D03*
X520068Y207142D03*
X516551Y214987D03*
X512160Y217073D03*
X526657Y207363D03*
X524405Y212531D03*
X514766Y208222D03*
X519183Y224173D03*
X519300Y220500D03*
X516625Y230075D03*
X515675Y234555D03*
X524675Y234766D03*
X517189Y226229D03*
X517670Y247527D03*
X515675Y254098D03*
X525480Y268959D03*
X518590Y310129D03*
X526250Y310940D03*
X519650Y320384D03*
X522420Y315475D03*
X517260Y315978D03*
X523930Y321642D03*
X514400Y340829D03*
X520510Y337299D03*
X527438Y340353D03*
X517617Y422944D03*
X514820Y417617D03*
X526440Y422428D03*
X527300Y417368D03*
X526440Y432077D03*
X515780Y434039D03*
X517929Y439676D03*
X523667Y438452D03*
X522379Y431974D03*
X513140Y452621D03*
X519440Y452321D03*
X526340D03*
X512867Y443679D03*
X516353Y443517D03*
X523838Y442723D03*
X513140Y459721D03*
Y466021D03*
X525640Y473021D03*
X519640D03*
X513140D03*
X516353Y480708D03*
X525603Y480187D03*
X525638Y484023D03*
X519490Y496645D03*
X525698Y496724D03*
X519938Y493125D03*
X524938D03*
X522250Y513692D03*
X514430Y511801D03*
X519430D03*
X527138Y529525D03*
X523938Y528725D03*
X515110Y528785D03*
X519438Y543025D03*
X513480Y541499D03*
X518938Y540425D03*
X521938Y540325D03*
X516380Y540364D03*
X525338Y540125D03*
X513838Y556925D03*
X516738Y562425D03*
X513738D03*
X512354Y590825D03*
X515413Y590950D03*
X524638Y590225D03*
X520228Y590335D03*
X519638Y600425D03*
X523538Y600325D03*
X527438D03*
X525570Y602466D03*
X514058Y605055D03*
X523800Y611145D03*
X520370Y625158D03*
X526300Y623621D03*
X518920Y615387D03*
X519830Y634663D03*
X511910Y638722D03*
X514320Y641085D03*
X515371Y658880D03*
X515438Y649996D03*
X525692Y654862D03*
X517328Y655529D03*
X521516Y650576D03*
X517806Y670102D03*
X517222Y673917D03*
X518800Y665776D03*
X526610Y672286D03*
X515541Y661845D03*
X526430Y664730D03*
X515425Y685783D03*
X518382Y678247D03*
X515429Y692278D03*
X526600Y679117D03*
X517888Y687901D03*
X518947Y685122D03*
X527111Y686052D03*
X515429Y697278D03*
X518500Y723073D03*
X512548Y722093D03*
X514620Y713193D03*
X517443Y717011D03*
X517775Y711203D03*
X522865Y711178D03*
X514498Y716473D03*
X519440Y735681D03*
X512140Y736554D03*
X514901Y724120D03*
X523370Y724131D03*
X516940Y735683D03*
X521800Y732667D03*
X514420Y733131D03*
X524576Y733227D03*
X512610Y747115D03*
X525110Y774395D03*
X519440Y772861D03*
X519746Y791476D03*
X515809D03*
X542180Y93534D03*
X539510Y108742D03*
X542248Y106333D03*
X536955Y100257D03*
X532955Y108669D03*
X535960Y112850D03*
X527613Y113373D03*
X542700Y112881D03*
X527898Y147146D03*
X538655Y151415D03*
X538294Y159415D03*
X533483Y177449D03*
X533797Y180764D03*
X529272Y178311D03*
X542002Y180100D03*
X539500Y196500D03*
X536232Y192086D03*
X529592Y192999D03*
X533474Y196500D03*
X541657Y207645D03*
X532320Y209470D03*
X538525Y213425D03*
X532500Y206500D03*
X536676Y234993D03*
X534208Y227832D03*
X528105Y230594D03*
X536576Y246993D03*
X539438Y250323D03*
X536972Y242993D03*
X536476Y238993D03*
X535772Y250076D03*
X529527Y265584D03*
X539267Y267102D03*
X532794Y282068D03*
X530119Y280101D03*
X528680Y317349D03*
X541380Y340358D03*
X543110Y333848D03*
X536180Y341432D03*
X536170Y336603D03*
X531795Y340409D03*
X531430Y337074D03*
X527603Y337208D03*
X529910Y419478D03*
X540700Y418852D03*
X541650Y422280D03*
X536440Y421973D03*
X530940Y422207D03*
X541440Y431787D03*
X536440Y431923D03*
X531440Y432178D03*
X529968Y440216D03*
X529028Y430469D03*
X535352Y440414D03*
X542738Y455823D03*
X530038Y444323D03*
X533040Y453221D03*
X540141Y442994D03*
X534738Y445523D03*
X541838Y450723D03*
X533740Y458021D03*
Y465021D03*
X542738Y463123D03*
X533740Y473021D03*
X540938Y473623D03*
X535729Y476632D03*
X539419Y491107D03*
X532934Y491384D03*
X538038Y488323D03*
X533038D03*
X543280Y491040D03*
X530438Y529525D03*
X541538Y529625D03*
X534401Y529562D03*
X530638Y539525D03*
X534638Y539825D03*
X541238Y539625D03*
X528138Y539925D03*
X533038Y590325D03*
X540701Y590162D03*
X527638Y590325D03*
X535776Y590487D03*
X530338Y590325D03*
X536438Y600425D03*
X542438Y613723D03*
X529408Y603485D03*
X540540Y601008D03*
X538828Y602945D03*
X542848Y602975D03*
X535048Y602885D03*
X538400Y613804D03*
X541980Y620227D03*
X527828Y615387D03*
X532420Y615484D03*
X540048Y629641D03*
X539471Y632476D03*
X530779Y637354D03*
X532479Y633588D03*
X535230Y648711D03*
X541440Y647594D03*
X531970Y650491D03*
X542424Y654821D03*
X536557Y655498D03*
X539120Y670129D03*
X529525Y669349D03*
X529899Y661020D03*
X539734Y675020D03*
X539830Y667332D03*
X531599Y689838D03*
X533270Y679351D03*
X531597Y697509D03*
X535485Y715182D03*
X535272Y711217D03*
X535062Y708679D03*
X530012Y708618D03*
X543193Y710787D03*
X539577Y721891D03*
X537503Y710088D03*
X528388Y722903D03*
X540062Y708779D03*
X537702Y735662D03*
X541940Y735681D03*
X528440D03*
X531845Y724095D03*
X532940Y734810D03*
X531029Y733142D03*
X539650Y780942D03*
X529300Y771341D03*
X533600Y778780D03*
X539431Y791476D03*
X535494D03*
X547248Y106582D03*
X555938Y97292D03*
X551454Y97154D03*
X547480Y96632D03*
X557995Y110244D03*
X546306Y110193D03*
X550490Y112989D03*
X548367Y135415D03*
X548007Y139415D03*
X552173Y138528D03*
X550599Y132596D03*
X547543Y143415D03*
X550550Y151682D03*
X558059Y154254D03*
X558348Y142511D03*
X551464Y143862D03*
X550604Y168072D03*
X558845Y158697D03*
X550370Y157461D03*
X557668Y176534D03*
X555510Y173872D03*
X551395Y174172D03*
X555836Y179259D03*
X546000Y180000D03*
X558768Y191223D03*
X544500Y197500D03*
X546000Y192000D03*
X553909Y207401D03*
X547927Y212190D03*
X558416Y210682D03*
X544700Y216100D03*
X549909Y207060D03*
X557909Y207537D03*
X555750Y212029D03*
X544500Y207000D03*
X547148Y220220D03*
X545424Y226722D03*
X546690Y233066D03*
X544990Y231086D03*
X549488Y233003D03*
X549358Y230153D03*
X552120Y232388D03*
X552050Y229124D03*
X550040Y243929D03*
X545703Y245725D03*
X545981Y236287D03*
X550090Y247079D03*
X545116Y266847D03*
X547929Y258102D03*
X557207Y274828D03*
X551341Y274262D03*
X545223Y276895D03*
X557207Y280328D03*
X555072Y289563D03*
X557222Y285109D03*
X553690Y340829D03*
X547340Y339103D03*
X555707Y389146D03*
X552090Y388953D03*
X548470Y378127D03*
X549760Y407251D03*
X553230D03*
X553750Y410420D03*
X544500Y422583D03*
X557017Y438968D03*
X549574Y432582D03*
X543381Y448428D03*
X556771Y456156D03*
X556959Y443009D03*
X551140Y445789D03*
X555140Y445940D03*
X546384Y445107D03*
X547488Y452373D03*
X556971Y460656D03*
X554550Y469674D03*
X545513Y469740D03*
X543338Y459323D03*
X547638Y462356D03*
X546038Y457523D03*
X547340Y484025D03*
X546250Y490302D03*
X548000Y509493D03*
X547880Y515743D03*
X544370Y510267D03*
Y515267D03*
X544138Y530125D03*
X554860Y531701D03*
X549920Y527242D03*
X545413Y547950D03*
X551161Y547148D03*
X545138Y539725D03*
X551538Y540325D03*
X551338Y544225D03*
X551438Y561225D03*
X551338Y551100D03*
X551438Y563825D03*
X551538Y568525D03*
X551238Y571725D03*
X550938Y587325D03*
X547000Y590163D03*
X551238Y584025D03*
X543850Y590313D03*
X548138Y600425D03*
X544638Y600525D03*
X553619Y601204D03*
X550149Y604639D03*
X546938Y613828D03*
X543400Y625963D03*
X552350Y614028D03*
X552849Y631652D03*
X558281Y637840D03*
X551030Y637200D03*
X543400Y635615D03*
X545377Y647594D03*
X549314D03*
X551230Y652844D03*
X555356Y665156D03*
Y669156D03*
X555308Y673156D03*
X551283Y670800D03*
X555357Y689156D03*
X555284Y685156D03*
X555235Y681156D03*
X555308Y677156D03*
X547346Y697581D03*
X544984Y699419D03*
X551283Y699243D03*
X555150Y697156D03*
X555271Y693156D03*
X547542Y711523D03*
X544934Y720820D03*
X550535Y721903D03*
X555551Y722342D03*
X557488Y713709D03*
X553725Y717251D03*
X550004Y709559D03*
X555062Y708679D03*
X545062D03*
X555148Y735583D03*
X550940Y735681D03*
X546440D03*
X553193Y724847D03*
X546566Y724119D03*
X544082Y724460D03*
X549049Y724412D03*
X557426Y724436D03*
X557978Y734053D03*
X545300Y783152D03*
X550940Y771858D03*
X554870Y779438D03*
X555179Y791476D03*
X566090Y109136D03*
X560938Y97195D03*
X569559Y103123D03*
X565938Y96820D03*
X563230Y150222D03*
X564076Y145372D03*
X563410Y165289D03*
X563274Y162169D03*
X562195Y159015D03*
X563129Y178369D03*
X559646Y174476D03*
X569682Y195199D03*
X572782D03*
X561909Y207393D03*
X569874Y231795D03*
X572690Y226569D03*
X572020Y222393D03*
X567980Y222353D03*
X568410Y226647D03*
X561258Y230153D03*
X566248Y230283D03*
X563506Y232027D03*
X571576Y246693D03*
X564676D03*
X571476Y260093D03*
X564676D03*
Y253693D03*
X564274Y279395D03*
X566774Y275195D03*
X566876Y289890D03*
X561525Y298192D03*
X560865Y285434D03*
X565953Y301635D03*
X567320Y415088D03*
X565310Y412700D03*
X565977Y456156D03*
X566059Y460956D03*
X572440Y464323D03*
Y469323D03*
X562340Y484252D03*
X561610Y503885D03*
X560960Y510151D03*
X571830Y509411D03*
X573840Y512108D03*
X564370Y504117D03*
Y509117D03*
X567791Y528325D03*
X568068Y525306D03*
X567493Y532225D03*
X561065Y543998D03*
X560838Y540325D03*
X562308Y536895D03*
X566298Y548465D03*
X563188Y541925D03*
X566338Y554235D03*
X561174Y564471D03*
X574738Y579525D03*
X565858Y576195D03*
X561198Y581793D03*
X566378Y567725D03*
X561608Y571775D03*
X574537Y591325D03*
X574738Y587425D03*
X574645Y583525D03*
X565398Y584765D03*
X568163Y595115D03*
X561568Y589355D03*
X574071Y606204D03*
X568930Y607754D03*
X566053Y627509D03*
X571650Y625998D03*
X574730Y625521D03*
X565647Y637705D03*
X565556Y632431D03*
X571790Y646799D03*
X559440Y650767D03*
X566950Y659439D03*
X563850Y659575D03*
X563840Y653515D03*
X565168Y664614D03*
Y674614D03*
Y669614D03*
Y684614D03*
X563586Y682137D03*
X563577Y692284D03*
X563441Y676872D03*
X565168Y679614D03*
X563393Y686908D03*
X565168Y689614D03*
X568215Y702343D03*
X565168Y694614D03*
Y699614D03*
X568288Y715547D03*
X560544Y718091D03*
X569604Y721248D03*
X574190Y717805D03*
X564319Y721587D03*
X562540Y713454D03*
X560062Y708679D03*
X570614Y713237D03*
X565062Y708679D03*
X568908Y735883D03*
X573440Y735681D03*
X564438Y735853D03*
X560350Y735807D03*
X573440Y724053D03*
X568940Y724090D03*
X562395Y724557D03*
X571232Y732545D03*
X566798Y734023D03*
X569680Y771106D03*
X560150Y781347D03*
X562700Y772391D03*
X572720Y777184D03*
X559116Y791476D03*
X578938Y103123D03*
X588943Y98963D03*
X589308Y103990D03*
X583829Y117732D03*
X583661Y121836D03*
X580501Y138336D03*
X583829Y132232D03*
X583547Y128232D03*
X587968Y138765D03*
X581565Y154969D03*
X583970Y144589D03*
X580180Y148894D03*
X579540Y143304D03*
X579897Y161355D03*
X584438Y160933D03*
X582792Y167632D03*
X581915Y179955D03*
X582920Y194220D03*
X588692Y192809D03*
X585580Y210516D03*
X579707Y220662D03*
X583707Y220762D03*
X587707Y220728D03*
X579707Y229395D03*
X585579Y230095D03*
X576105Y231626D03*
X578076Y246693D03*
Y253393D03*
Y260093D03*
X575874Y282395D03*
X581474Y274795D03*
X575874Y289895D03*
Y285995D03*
X575880Y293016D03*
X575908Y295606D03*
X583853Y313783D03*
X585584Y308881D03*
X579168Y313641D03*
X588607Y305034D03*
X576650Y311446D03*
X581650D03*
X583737Y321204D03*
X585984Y323246D03*
X579788Y354743D03*
X589070Y423525D03*
X578830Y448192D03*
X575550Y463784D03*
X575650Y469996D03*
X588153Y459599D03*
X579600Y508878D03*
X578840Y512108D03*
X585013Y547959D03*
X575438Y545425D03*
X589036Y548825D03*
X583890Y537093D03*
X576208Y542405D03*
X575838Y548935D03*
X575238Y552025D03*
X588540Y557418D03*
X584413Y563198D03*
X583538Y552225D03*
X575038Y554725D03*
X575138Y559825D03*
X577778Y556355D03*
X575038Y567725D03*
X575538Y571725D03*
X574876Y575625D03*
X578110Y582149D03*
X582023Y571242D03*
X586369Y585801D03*
X578399Y585696D03*
X588780Y611056D03*
X586810Y603344D03*
X579500Y625963D03*
X577000Y620029D03*
X585500Y620926D03*
X588780Y616056D03*
X587440Y656958D03*
X576700Y655594D03*
X588950Y650070D03*
X583930Y652439D03*
X579020Y658250D03*
X577217Y652002D03*
X576987Y660180D03*
X580740Y653286D03*
X584903Y663828D03*
X580637Y663629D03*
X576846Y675985D03*
X579076Y669603D03*
X576520Y667750D03*
X586060Y682582D03*
X587040Y688218D03*
X589050Y680160D03*
X579980Y683140D03*
X576644Y679562D03*
X578030Y690236D03*
X577010Y682718D03*
X576519Y687665D03*
X589500Y690546D03*
X586995Y694080D03*
X579151Y707857D03*
X588151D03*
X584101Y707893D03*
X576442Y705492D03*
X585400Y697289D03*
X584312Y710716D03*
X579220Y720776D03*
X585693Y722428D03*
X583440Y735856D03*
X587940Y735681D03*
X587963Y724108D03*
X577940Y724127D03*
X583440Y724927D03*
X577570Y734118D03*
X580510Y724421D03*
X587170Y773768D03*
X579240Y775147D03*
X578802Y791476D03*
X574864D03*
X603158Y91535D03*
X601374Y94048D03*
X604543Y94886D03*
X598123Y102023D03*
X595318Y98854D03*
X593850Y103755D03*
X592392Y100623D03*
X594920Y123370D03*
X595345Y120216D03*
X605070Y123991D03*
X600118Y112568D03*
X592938Y117657D03*
X595438Y138130D03*
X592938Y140689D03*
Y133232D03*
X594938Y127893D03*
X593537Y161023D03*
X592917Y171906D03*
X592491Y175906D03*
X593277Y179955D03*
X595707Y220995D03*
X591707Y221095D03*
Y230162D03*
X597074Y239995D03*
X600874Y239795D03*
X604774Y249795D03*
X596774D03*
X600874D03*
X604674Y239995D03*
X592874Y250995D03*
X605674Y236295D03*
X595374Y236795D03*
X592858Y247079D03*
X593459Y240780D03*
X594067Y265168D03*
X594174Y256695D03*
X593874Y262395D03*
X596574Y268695D03*
X600674Y268795D03*
X604574D03*
X604926Y278476D03*
X604774Y271893D03*
X590874Y275195D03*
X594374Y271395D03*
X596574Y276393D03*
X592201Y308988D03*
X593607Y305034D03*
X591977Y319360D03*
X590984Y323246D03*
X598551Y329541D03*
X601450Y326509D03*
X604338Y338285D03*
X600770Y358702D03*
X605746Y387837D03*
X597440Y391690D03*
X605573Y393920D03*
X594860Y395088D03*
X600680Y412780D03*
X590720Y456076D03*
X591100Y450128D03*
X605800Y463167D03*
X603819Y485332D03*
X605798Y501238D03*
X598670Y508170D03*
X596751Y532108D03*
X603010Y527908D03*
X606300Y551844D03*
X604820Y555040D03*
X604437Y557956D03*
X596050Y557563D03*
X596530Y574903D03*
X596495Y578903D03*
X592437Y566543D03*
X601043Y567781D03*
X596484Y582903D03*
X596209Y586903D03*
X590898Y597158D03*
X605396Y590552D03*
X605286Y584152D03*
X605290Y594166D03*
X596401Y589852D03*
X593867Y595695D03*
X605521Y601097D03*
X590842Y608112D03*
X591023Y600384D03*
X605362Y609413D03*
X602314Y607641D03*
Y602641D03*
X593867Y600695D03*
X590646Y618751D03*
X605010Y641435D03*
X600980Y641533D03*
X594733Y653385D03*
X591279Y656223D03*
X596998Y658008D03*
X591840Y659568D03*
X596470Y655231D03*
X601588Y664798D03*
X602332Y671156D03*
X600736Y668425D03*
X593142Y663828D03*
X600719Y675156D03*
X597300Y663128D03*
X600690Y691896D03*
X600727Y681876D03*
X602020Y679156D03*
X600727Y686876D03*
X604220Y703774D03*
X600650Y707835D03*
X592960Y703291D03*
X592440Y723768D03*
X596860Y723422D03*
X601856Y711479D03*
X606146Y713145D03*
X601813Y715579D03*
X598880Y719232D03*
X595950Y708997D03*
X594170Y719290D03*
X601440Y735681D03*
X605938Y735665D03*
X596940Y735681D03*
X593004Y735662D03*
X603938Y753623D03*
X606270Y774615D03*
X597530Y780191D03*
X592480Y771514D03*
X598487Y791476D03*
X594550D03*
X618623Y108918D03*
X610543Y107678D03*
X617925Y114064D03*
X613432Y153528D03*
X608274Y249795D03*
X608774Y239995D03*
X610415Y237441D03*
X617778Y238873D03*
X608274Y268795D03*
X612974Y269095D03*
X609150Y328514D03*
X616490Y327534D03*
X613640Y336986D03*
X607671Y344818D03*
X619190Y336986D03*
X608306Y359971D03*
X611848Y359784D03*
X607855Y352341D03*
X618581Y354818D03*
X617592Y362539D03*
X620238Y364369D03*
X609078Y388557D03*
X608869Y396959D03*
X608821Y403445D03*
X619014Y408353D03*
X609078Y393557D03*
X612641Y397478D03*
Y402478D03*
X611050Y423087D03*
X621399Y420400D03*
X611130Y417928D03*
X616258Y422211D03*
X610580Y448662D03*
X609370Y452974D03*
X610010Y456581D03*
X617980Y460408D03*
X621760Y526967D03*
X609300Y531638D03*
X613541Y546764D03*
X613470Y537495D03*
X616320Y537066D03*
X609168Y554851D03*
X610070Y557588D03*
X621937Y558276D03*
X621840Y555040D03*
X609060Y552101D03*
X607077Y566915D03*
X610821Y566494D03*
X621937Y567143D03*
X609026Y579132D03*
X617270Y580443D03*
X611520Y596594D03*
X612270Y586543D03*
X612493Y607666D03*
X611254Y617943D03*
X612370Y614143D03*
X615690Y625536D03*
X614579Y645072D03*
X616730Y633290D03*
X608310Y641603D03*
X611572Y629894D03*
X620510Y639427D03*
X616471Y636215D03*
X613796Y648705D03*
X612950Y656140D03*
X607620Y647169D03*
X615700Y657757D03*
X610651Y675156D03*
X614909Y671938D03*
X613200Y661577D03*
X620160Y670594D03*
X615940Y666862D03*
X617235Y689036D03*
X610693Y679333D03*
X610570Y691156D03*
X610550Y686640D03*
X610810Y683933D03*
X612670Y681438D03*
X612811Y688422D03*
X621410Y696941D03*
X607020Y704644D03*
X608975Y708094D03*
X612914Y707630D03*
X610540Y697964D03*
X618020Y700000D03*
X610570Y695156D03*
X607380Y699671D03*
X617930Y703520D03*
X620480Y693827D03*
X611244Y709830D03*
X621254Y713788D03*
X617093Y709167D03*
X609070Y721917D03*
X616070Y720838D03*
X613730Y717663D03*
X620670Y722216D03*
X620830Y717516D03*
X609840Y713617D03*
X619590Y735383D03*
X614732Y735517D03*
X608791Y735775D03*
X619080Y772610D03*
X619030Y778682D03*
X612260Y783106D03*
X609347Y778624D03*
X618172Y791476D03*
X614235D03*
X610298D03*
X626380Y85117D03*
X624020Y83243D03*
X623750Y87130D03*
X626380Y88518D03*
X623725Y90422D03*
X626180Y91919D03*
X623820Y93654D03*
X626320Y96084D03*
X623610Y97125D03*
X626180Y99276D03*
X628838Y120216D03*
X628738Y133012D03*
X624800Y184953D03*
Y179953D03*
X624358Y176090D03*
X632483Y192781D03*
X624950Y189801D03*
X632485Y202077D03*
X634962Y200121D03*
Y195121D03*
X622470Y261628D03*
X635000Y265400D03*
X634212Y281670D03*
X624101Y296525D03*
X624383Y292591D03*
X631672Y301066D03*
X632376Y305257D03*
X631702Y307880D03*
X632122Y312898D03*
X633773Y310439D03*
X635652Y313118D03*
X636962Y310928D03*
X623820Y321062D03*
X633470Y326710D03*
X628140Y317610D03*
X631860Y321455D03*
X627000Y327926D03*
X622890Y325227D03*
X633652Y315198D03*
X628141Y344818D03*
X630190Y336986D03*
X625190D03*
X624889Y357778D03*
X637738Y392034D03*
X636990Y386464D03*
X627022Y383713D03*
X634511Y389156D03*
X633633Y403717D03*
X637614Y397259D03*
X630691Y405007D03*
X636938Y402885D03*
X633663Y411009D03*
X630691Y410007D03*
X636586Y410910D03*
X633455Y427209D03*
X634578Y424964D03*
X635840Y449890D03*
X626250Y450248D03*
X631280Y446007D03*
X635120Y456136D03*
X630570Y451450D03*
X634945Y461888D03*
X635545Y465888D03*
X622100Y465822D03*
X625900Y461769D03*
X628250Y471142D03*
X632680Y466669D03*
X636010Y469995D03*
X630420Y491511D03*
X636170Y493028D03*
X622600Y488753D03*
X622199Y506535D03*
X632157Y511230D03*
X625130Y534199D03*
X634530Y521565D03*
X634190Y538267D03*
X632362Y565543D03*
X636890Y571351D03*
X624870Y573143D03*
X627084Y578257D03*
X634921Y580163D03*
X627047Y581066D03*
X636868Y593141D03*
X630768Y593241D03*
X624468D03*
Y612141D03*
X624368Y605941D03*
Y599741D03*
X629868Y612241D03*
X635968D03*
X623940Y628720D03*
X636890Y627095D03*
X629781Y628559D03*
X627986Y625895D03*
X630984Y624829D03*
X622510Y635544D03*
X634137Y631342D03*
X627146Y638932D03*
X623290Y641222D03*
X634137Y639352D03*
X630137Y639312D03*
X631930Y655254D03*
X634251Y683493D03*
X623940Y723503D03*
X633970Y723033D03*
X622290Y708516D03*
X628160Y722343D03*
X623960Y735141D03*
X628380Y735476D03*
X631690Y733744D03*
X635460Y735130D03*
X636170Y729335D03*
X630040Y745114D03*
X632300Y749755D03*
X636910Y745815D03*
X624010Y746351D03*
X629912Y769200D03*
X625010Y778281D03*
X636390Y775395D03*
X632030Y779137D03*
X632000Y775400D03*
X629983Y791476D03*
X633920D03*
X643957Y53688D03*
X639957Y53849D03*
X638970Y132241D03*
X639200Y170100D03*
X639350Y250123D03*
X640448Y294422D03*
X643170Y294282D03*
X641227Y297070D03*
X644113Y297071D03*
X653352Y291388D03*
X642932Y284768D03*
X649995Y296433D03*
X640171Y311965D03*
X644105D03*
X652362Y306598D03*
X651352Y323938D03*
X653162Y318398D03*
X650162D03*
X640647Y339854D03*
X648450Y338711D03*
X646013Y358110D03*
X648838Y349785D03*
X642863Y358010D03*
X639838Y349818D03*
X646171Y364676D03*
X648425Y373474D03*
X652139Y377125D03*
X647440Y386383D03*
X641236Y381616D03*
X645236Y377858D03*
X647340Y393283D03*
X647440Y408383D03*
X647340Y400083D03*
X651138Y417385D03*
X648493Y417221D03*
X641480Y430289D03*
X650079D03*
X648208Y427819D03*
X643208D03*
X653070Y427500D03*
X650822Y425295D03*
X641690Y443656D03*
X647280Y446851D03*
X653360Y446280D03*
X651080Y455238D03*
X652110Y465238D03*
X651840Y460012D03*
X648920Y457851D03*
X646600Y463571D03*
X648956Y469323D03*
X646381Y478679D03*
X650521Y482930D03*
X647921Y475778D03*
X646105Y492010D03*
X650790Y497730D03*
X650150Y494337D03*
X646906Y505210D03*
X638350Y507893D03*
X646460Y512967D03*
X652690Y531693D03*
X640470Y523266D03*
X645040Y524444D03*
X645150Y535704D03*
X638166Y560972D03*
X638286Y557415D03*
X643012Y565243D03*
X651437Y569676D03*
X639673Y576888D03*
X651437Y578943D03*
X646732Y580781D03*
X641870Y580743D03*
X646870Y569443D03*
Y576243D03*
X643568Y593241D03*
Y612341D03*
Y606641D03*
Y599541D03*
X644636Y627257D03*
X642795Y624818D03*
X648701Y624774D03*
X638470Y639290D03*
X650928D03*
X646940Y643448D03*
X641263Y631393D03*
X649173Y629876D03*
X646737Y639413D03*
X642737D03*
X647870Y649784D03*
X646580Y654775D03*
X651226Y666288D03*
X639940Y687841D03*
X640330Y684439D03*
X642999Y685781D03*
X648077Y713569D03*
X644950Y719110D03*
X653500Y732583D03*
X639928Y738905D03*
X638890Y734879D03*
X652660Y749000D03*
X639920Y753526D03*
X646680Y755009D03*
X646500Y746300D03*
X650400Y770522D03*
X638470Y762212D03*
X649640Y757527D03*
X646370Y759252D03*
X647410Y767053D03*
X651690Y778099D03*
X640010Y778215D03*
X652212Y786700D03*
X655947Y53677D03*
X659947Y53722D03*
X658769Y143630D03*
X658767Y151013D03*
X655642Y144915D03*
Y149915D03*
X658959Y165625D03*
X658972Y158337D03*
X655695Y159567D03*
Y164567D03*
X667300Y188112D03*
X660700Y203282D03*
X669250Y203317D03*
X665320Y203247D03*
X664560Y195018D03*
Y191443D03*
X660770Y214951D03*
X665390Y214916D03*
X661160Y235485D03*
X658582Y222614D03*
X658601Y229770D03*
X655030Y228744D03*
Y223744D03*
X661190Y246085D03*
X657838Y243407D03*
Y238407D03*
X660899Y311515D03*
X656270Y299379D03*
X654962Y307698D03*
X654060Y302459D03*
X659350Y298810D03*
X654352Y323938D03*
X655122Y315070D03*
X656730Y338633D03*
X666270Y359134D03*
X660138Y365885D03*
X659543Y377086D03*
X662390Y377039D03*
X653938Y364885D03*
X668925Y364887D03*
X663632Y366698D03*
X654340Y386283D03*
X661140D03*
X669215Y377488D03*
X654840Y408483D03*
X661940Y408383D03*
X666312Y417742D03*
X658295Y417662D03*
X653649Y417582D03*
X668779Y417135D03*
X663674Y417999D03*
X655812Y424106D03*
X656021Y427864D03*
X665766Y427868D03*
X663339Y425601D03*
X658339D03*
X664450Y435739D03*
X658680Y446610D03*
X664528Y463432D03*
X667428D03*
X666928Y468132D03*
X660458Y470932D03*
X659828Y465162D03*
X667774Y477992D03*
X661158Y486152D03*
X667070Y483608D03*
X662780Y477039D03*
X660518Y492862D03*
X662630Y500823D03*
X654240Y511568D03*
X653800Y505331D03*
X659933Y513927D03*
X664024Y513414D03*
X668573Y514155D03*
X668823Y532470D03*
X668627Y527718D03*
X659740Y536019D03*
X667050Y535324D03*
X665170Y595943D03*
X661396Y588900D03*
X655445Y591918D03*
X664603Y601976D03*
X658980Y610043D03*
X655978Y609635D03*
X656070Y612743D03*
X655688Y601761D03*
X664870Y614543D03*
X654645Y627064D03*
X667610Y617197D03*
X663560Y625019D03*
X659600Y623785D03*
X655873Y615540D03*
X655170Y639432D03*
X654221Y631425D03*
X656971Y660492D03*
X657550Y655072D03*
X668000Y676595D03*
X659978Y666274D03*
X656254Y683277D03*
X663040Y688057D03*
X665050Y680648D03*
X657340Y690286D03*
X655610Y706309D03*
X656505Y701191D03*
X654514Y720674D03*
X657320Y723584D03*
X654050Y718086D03*
X656650Y713057D03*
X659200Y721454D03*
X659300Y734119D03*
X654000Y736400D03*
X656660Y736218D03*
X655574Y728674D03*
X657570Y730414D03*
X658860Y727383D03*
X656000Y732400D03*
X657500Y761500D03*
X664460Y785890D03*
X657010Y786039D03*
X661479Y791476D03*
X665416D03*
X679927Y53881D03*
X675927Y53779D03*
X669987Y53672D03*
X670980Y77061D03*
X671810Y106472D03*
X670280Y188112D03*
X676590Y188198D03*
X680100Y188182D03*
X680220Y200725D03*
X678650Y203480D03*
X681770Y203514D03*
X682140Y191214D03*
Y194615D03*
X680310Y217357D03*
X678750Y214908D03*
X681870Y214942D03*
X669320Y214986D03*
X671129Y305579D03*
X671166Y302550D03*
X679590Y352829D03*
X679430Y350013D03*
X672752Y366160D03*
X679552Y372873D03*
X677083Y375124D03*
X669540Y386283D03*
X678099Y389915D03*
X674235Y379364D03*
X677946Y387211D03*
X678986Y392661D03*
X669440Y395183D03*
Y408483D03*
X669540Y402783D03*
X678338Y405185D03*
X679138Y397985D03*
X680017Y403143D03*
X678838Y407785D03*
X673368Y416621D03*
X671056Y426300D03*
X683128Y451332D03*
X680228Y451432D03*
X672660Y441007D03*
X673740Y449887D03*
X682764Y444832D03*
X677070Y444820D03*
X670428Y463532D03*
X669728Y468032D03*
X672628D03*
X672190Y457216D03*
X683112Y479786D03*
X679299Y491473D03*
X684876Y497385D03*
X674156Y503662D03*
X678450Y508438D03*
X680790Y504521D03*
X677160Y529422D03*
X675044Y524581D03*
X678315Y540752D03*
X678360Y557426D03*
X673950Y557314D03*
X677850Y562515D03*
X673700D03*
X677730Y567706D03*
X673590Y567696D03*
X670940Y612070D03*
X683720Y631732D03*
X681310Y666671D03*
X671400Y666151D03*
X678386Y668420D03*
X673386D03*
X669390Y695406D03*
X672630Y720752D03*
X675100Y749300D03*
X672710Y746235D03*
X672500Y749179D03*
X684500Y786665D03*
X676390Y778439D03*
X677490Y782114D03*
X673290Y782855D03*
X677227Y786454D03*
X669320Y783845D03*
X681480Y777388D03*
X681164Y783461D03*
X669810Y786721D03*
X672500Y779579D03*
X683520Y789080D03*
Y792080D03*
X688160Y64459D03*
X689500Y120441D03*
X691148Y140140D03*
X698150Y136791D03*
X691280Y149571D03*
X691314Y145071D03*
X687546Y154228D03*
X699990Y149631D03*
X700060Y144981D03*
X687571Y172292D03*
X693520Y186376D03*
X697850Y186441D03*
X689820Y200159D03*
Y203491D03*
X689480Y191144D03*
Y194615D03*
X691970Y216820D03*
X691690Y212100D03*
X693540Y205721D03*
X697800Y205879D03*
X692010Y221158D03*
X687584Y233034D03*
Y251770D03*
X689864Y392130D03*
X686686Y392522D03*
X687869Y386780D03*
X688118Y381043D03*
X687121Y407004D03*
X689864Y398141D03*
X686686Y397522D03*
X689527Y407843D03*
X685859Y403970D03*
X691037Y401739D03*
X686731Y413349D03*
X689527Y412843D03*
X687130Y464132D03*
X691070Y464058D03*
X689017Y497282D03*
X694823Y498932D03*
X691161Y518684D03*
X692520Y506898D03*
X696494Y513677D03*
X689729Y509580D03*
X696891Y507279D03*
X700719Y516954D03*
X686770Y543325D03*
X691532Y559789D03*
Y563789D03*
Y567789D03*
Y571789D03*
Y575789D03*
Y579789D03*
Y583789D03*
Y587789D03*
X695600Y590788D03*
X685410Y621250D03*
X688340Y621294D03*
X687660Y631799D03*
X685640Y634154D03*
X692720Y670540D03*
X698830Y670652D03*
X698386Y667241D03*
X693386D03*
X689100Y680291D03*
X688510Y735294D03*
X699600Y776000D03*
X689700Y774500D03*
X707176Y50574D03*
X711676Y51019D03*
X706380Y75482D03*
X708130Y106389D03*
X701687Y212132D03*
X700947Y216868D03*
X700994Y221368D03*
X701770Y331938D03*
X707942Y448676D03*
X714639Y454872D03*
X712239Y452293D03*
X702730Y455483D03*
X704550Y444407D03*
X715528Y459332D03*
X710768Y475972D03*
X715328Y481122D03*
X704766Y498880D03*
X713978Y498075D03*
X716021Y516945D03*
X700829Y504041D03*
X707920Y505575D03*
X712281Y525785D03*
X706361Y532632D03*
X716260Y525295D03*
X710585Y539103D03*
X701170Y538508D03*
X701023Y553658D03*
X710873Y563230D03*
X713300Y578995D03*
X713190Y583032D03*
X712740Y593101D03*
X715282Y620282D03*
X711612Y620383D03*
X712732Y631749D03*
X716064D03*
X713742Y634373D03*
X703570Y673036D03*
X707660Y673204D03*
X708386Y669774D03*
X703386D03*
X713910Y681330D03*
X713445Y677641D03*
X708450Y695489D03*
X705870Y721832D03*
X709500Y736800D03*
X706575Y740425D03*
X704000Y770800D03*
X716245Y765576D03*
X704786Y791274D03*
X708723Y791092D03*
X709040Y787507D03*
X719800Y24920D03*
X726160Y109316D03*
X726190Y105325D03*
X726160Y112508D03*
X726500Y123466D03*
X726400Y130303D03*
X726470Y126659D03*
X731566Y442136D03*
X726580Y455637D03*
X731570Y464043D03*
X726430Y465371D03*
X726830Y460815D03*
X727940Y469943D03*
X731340Y476723D03*
X720140Y478333D03*
X718431Y483368D03*
X721290Y484381D03*
X719370Y472436D03*
X725730Y486788D03*
X729640Y486848D03*
X727602Y500100D03*
X720150Y491632D03*
X729942Y515757D03*
X719332D03*
X719761Y532432D03*
X728661Y558934D03*
X731251Y558975D03*
X726154Y559002D03*
X720445Y558990D03*
X723370Y558906D03*
X720052Y620480D03*
X719092Y631682D03*
X717372Y634474D03*
X727830Y641829D03*
X728690Y649829D03*
X718510Y681526D03*
X721100Y689400D03*
X718445Y677641D03*
X731200Y716200D03*
X729500Y737400D03*
X730800Y728400D03*
X729500Y746300D03*
X718150Y763015D03*
X721100Y762903D03*
X721245Y765576D03*
X727570Y775278D03*
X730990Y775334D03*
X726925Y778490D03*
X731925D03*
X721790Y791408D03*
X722590Y787885D03*
X738620Y109351D03*
X738650Y105360D03*
X744760Y103711D03*
X744790Y106938D03*
X747710Y100293D03*
X738620Y112543D03*
X738370Y123395D03*
X745070Y110183D03*
X738270Y130232D03*
X738340Y126588D03*
X747080Y129815D03*
X747600Y323527D03*
X745220Y327250D03*
X741401Y454832D03*
X736310Y450774D03*
X737350Y464330D03*
Y459823D03*
X742779Y487639D03*
X743364Y478975D03*
X743150Y483502D03*
X738130Y502748D03*
X732817Y489435D03*
X734575Y492575D03*
X745500Y492500D03*
X744020Y566143D03*
X744090Y575066D03*
X743951Y578833D03*
X744050Y571834D03*
X747470Y585542D03*
X747460Y582318D03*
X744000Y647919D03*
X733210Y645829D03*
X732540Y653829D03*
X734460Y788654D03*
Y791654D03*
X762590Y106529D03*
X762630Y103302D03*
X751080Y100293D03*
X754580Y124020D03*
X748070Y110209D03*
X751180D03*
X754610Y127247D03*
X750930Y129815D03*
X750430Y314330D03*
X750350Y311343D03*
X750700Y323771D03*
X753230Y328262D03*
X759400Y334839D03*
X754850Y335055D03*
X755500Y337791D03*
X758223Y446532D03*
X757823Y451032D03*
X748723Y455332D03*
X758500Y469500D03*
X757500Y474000D03*
X748300Y496800D03*
X751730Y583047D03*
X752960Y653967D03*
X749520Y658372D03*
X765250Y357789D03*
X765610Y361194D03*
X766840Y561290D03*
X766920Y564080D03*
X766950Y558318D03*
X766820Y569897D03*
X766900Y567233D03*
Y572869D03*
X771110Y578643D03*
X770850Y575760D03*
X770710Y584054D03*
X770850Y587025D03*
G54D16*
X10859Y109561D03*
X20859D03*
X83740Y20708D03*
X78740Y30708D03*
X73740Y20708D03*
X507489Y360278D03*
X713661Y20708D03*
X708661Y30708D03*
X703661Y20708D03*
X712975Y155655D03*
Y165455D03*
Y173455D03*
Y183255D03*
Y234461D03*
Y244261D03*
Y252261D03*
Y262061D03*
X723275Y155655D03*
Y165455D03*
Y173455D03*
Y183255D03*
Y234461D03*
Y244261D03*
Y252261D03*
Y262061D03*
G54D32*
X399606Y377165D03*
X413386Y363385D03*
X403543Y367322D03*
Y387008D03*
X413386Y390945D03*
X427166Y377165D03*
X423229Y367322D03*
Y387008D03*
G54D20*
X40749Y150808D03*
Y249194D03*
G54D38*
X546181Y81889D03*
X556181D03*
G54D11*
X-44872Y125213D03*
Y141213D03*
Y232533D03*
D03*
Y248533D03*
D03*
Y738493D03*
Y754493D03*
X-26872Y125213D03*
Y141213D03*
Y232533D03*
D03*
Y248533D03*
D03*
Y738493D03*
Y754493D03*
G54D19*
X36024Y187233D03*
Y181225D03*
Y205257D03*
Y199249D03*
Y193241D03*
Y217272D03*
Y211264D03*
X41930Y184229D03*
Y178221D03*
Y202253D03*
Y196245D03*
Y190237D03*
Y220276D03*
Y214268D03*
Y208260D03*
G54D28*
X154307Y507507D03*
X154517Y513931D03*
X154038Y511386D03*
X153967Y517186D03*
X159185Y531356D03*
X153731Y520734D03*
X162335Y521906D03*
X155400Y533436D03*
X154246Y527468D03*
X162335Y528206D03*
X159186Y534504D03*
X159185Y543953D03*
X155060Y545526D03*
X154945Y542383D03*
Y536083D03*
Y539233D03*
X159185Y547103D03*
X154900Y548682D03*
X162315Y553391D03*
X154900Y551832D03*
X159186Y553402D03*
X157611Y557468D03*
X154410Y557990D03*
X178818Y274540D03*
X178085Y518755D03*
X168617Y525756D03*
X172371Y519783D03*
X174720Y531356D03*
X178117Y528187D03*
X178082Y537654D03*
X178099Y550267D03*
X174105Y542290D03*
X167027Y539526D03*
Y536376D03*
X173217Y536556D03*
X181818Y274540D03*
X186417Y518526D03*
X186467Y514036D03*
X184920Y508626D03*
X181232Y515607D03*
X187417Y508756D03*
X189007Y514846D03*
X181232Y528205D03*
X187875Y534128D03*
X181232Y543953D03*
X184384Y537656D03*
X181232Y537654D03*
X184384Y543955D03*
X188927Y537836D03*
X190434Y546870D03*
X188383Y556895D03*
X184386Y553406D03*
X208050Y528883D03*
X209886Y539962D03*
X201509Y539853D03*
X207309Y539953D03*
X199709Y551653D03*
X208109Y551053D03*
X216184Y268587D03*
X214626Y516492D03*
X227326Y505741D03*
X227329Y508894D03*
X223709Y505353D03*
X216564Y528902D03*
X214118Y528583D03*
X218751Y543835D03*
X233626Y502591D03*
X230476D03*
X243075D03*
X230476Y505741D03*
X236776Y508891D03*
Y518339D03*
X233626Y508891D03*
Y515190D03*
X230476D03*
X233626Y518339D03*
X236776Y512040D03*
X243075Y508891D03*
X236776Y515190D03*
X230476Y518339D03*
Y512040D03*
X239925Y518339D03*
X233626Y521489D03*
Y527788D03*
X230476Y534087D03*
X236776Y521489D03*
Y527788D03*
Y524639D03*
X230476D03*
X233626Y534087D03*
X230476Y527788D03*
Y521489D03*
X239925Y534087D03*
Y521489D03*
X233626Y543536D03*
X239925Y540386D03*
Y543536D03*
X236776Y537236D03*
X230476D03*
Y543536D03*
Y540386D03*
X233626D03*
X236776Y543536D03*
X233626Y537236D03*
X239925D03*
X243075Y559284D03*
Y552984D03*
X231209Y566282D03*
X252524Y502591D03*
X255673D03*
X249374D03*
X246224D03*
X255673Y512040D03*
X252524D03*
X255673Y508891D03*
Y505741D03*
X249374D03*
Y508891D03*
X252524Y505741D03*
Y508891D03*
Y527789D03*
Y524639D03*
X255673Y534088D03*
X252524D03*
X249374D03*
X255673Y524639D03*
Y527789D03*
X249374D03*
Y524639D03*
X255673Y537237D03*
X249374D03*
X252524D03*
X255673Y540387D03*
X249374D03*
X252524D03*
Y549835D03*
X255673D03*
Y565580D03*
Y552984D03*
Y556133D03*
Y559282D03*
Y562431D03*
X249344Y552984D03*
Y556134D03*
X246224Y559284D03*
Y556134D03*
Y562434D03*
X252554Y559314D03*
X262904Y293850D03*
X268943Y291086D03*
X265122Y502591D03*
X274582D03*
X271402Y499441D03*
X271429Y496295D03*
X261972Y502591D03*
X268272Y505741D03*
Y508891D03*
Y512040D03*
X271422D03*
X265121Y508891D03*
X261972D03*
Y505741D03*
X265122D03*
X261972Y521489D03*
X268272Y534088D03*
X265122D03*
X261972D03*
X268272Y524639D03*
Y527789D03*
X265122D03*
Y524639D03*
X261972D03*
Y527789D03*
X268272Y521489D03*
X265122D03*
X268272Y540387D03*
X265122D03*
X261972D03*
X265122Y537237D03*
X268272D03*
X261972D03*
X268272Y549836D03*
X271421D03*
X274571Y552985D03*
X265122D03*
X268272Y559291D03*
X271422Y562434D03*
X271421Y556135D03*
X271422Y559291D03*
X261973Y552985D03*
X262009Y556153D03*
X261972Y562431D03*
X271422Y565583D03*
X271421Y552985D03*
X274572Y556142D03*
X284024Y499445D03*
X287173D03*
X277712Y502595D03*
X290323Y534092D03*
X280874D03*
X287174D03*
X284024D03*
X277725D03*
Y527792D03*
X280874Y537241D03*
Y543541D03*
X284024D03*
X287174Y540391D03*
X290323D03*
X277725D03*
Y543541D03*
Y537241D03*
X290322Y549841D03*
X280872D03*
X287174Y559289D03*
X284024Y565588D03*
X287174D03*
X290323Y556140D03*
X287174Y562438D03*
X280874D03*
X284024D03*
Y559289D03*
X280874D03*
X277725Y556135D03*
Y559289D03*
X287174Y556139D03*
X280874Y552989D03*
X287174D03*
X284024D03*
X293473Y534092D03*
Y540391D03*
Y559290D03*
X679175Y464038D03*
X674353Y463842D03*
X683112Y464038D03*
Y483723D03*
X683113Y471941D03*
X683112Y487660D03*
X687049Y467975D03*
X698860D03*
Y471912D03*
X690986D03*
Y479786D03*
X687049Y483723D03*
X698860Y479786D03*
Y483723D03*
X698683Y487517D03*
X690986Y487660D03*
X687049D03*
X692955Y502112D03*
X702797Y464038D03*
X706734Y471913D03*
Y483723D03*
X710671Y479786D03*
X706734Y475850D03*
X710671Y471913D03*
X702585Y483749D03*
X706734Y479786D03*
G54D31*
X354348Y38554D03*
X393718D03*
G54D36*
X507489Y281538D03*
G54D40*
X605796Y174845D03*
Y189845D03*
Y204845D03*
X611702Y185690D03*
Y178997D03*
Y200690D03*
Y193997D03*
G54D39*
X590999Y69167D03*
Y77041D03*
Y84915D03*
Y92789D03*
X615657Y69167D03*
Y77041D03*
Y84915D03*
Y92789D03*
G54D37*
X514780Y28803D03*
X524780D03*
X514780Y38803D03*
X524780D03*
X534780Y28803D03*
X544780D03*
X534780Y38803D03*
X544780D03*
X554780Y28803D03*
Y38803D03*
X577371Y28803D03*
X587371D03*
X577371Y38803D03*
X587371D03*
X597371Y28803D03*
X607371D03*
X597371Y38803D03*
X607371D03*
X617371Y28803D03*
Y38803D03*
X639963Y28803D03*
Y38803D03*
X649963Y28803D03*
Y38803D03*
X659963Y28803D03*
X669963D03*
X659963Y38803D03*
X669963D03*
X679963Y28803D03*
Y38803D03*
G54D24*
X80490Y420690D03*
Y423690D03*
X86050Y428718D03*
X80490Y426690D03*
X79900Y439193D03*
X86050Y437470D03*
Y434470D03*
X79900Y445193D03*
Y442193D03*
X86050Y443432D03*
Y446432D03*
X90031Y421693D03*
X90238Y418623D03*
X275766Y52772D03*
X275800Y50212D03*
X414870Y455166D03*
Y450976D03*
X412088Y521721D03*
X421710Y424527D03*
X430340Y416573D03*
X432450Y418766D03*
X422120Y418288D03*
X432960Y414886D03*
X422080Y414644D03*
Y410454D03*
X421770Y433187D03*
X422860Y441790D03*
X422760Y445581D03*
X425870Y449509D03*
X422460Y449467D03*
X429670Y449552D03*
X419420Y453168D03*
Y457358D03*
X446660Y413325D03*
X446950Y417162D03*
X438390Y456129D03*
X438520Y452324D03*
X433720Y449467D03*
X458598Y77967D03*
G54D29*
X175921Y301920D03*
X178921D03*
X188418Y278887D03*
X191054Y294424D03*
X183254Y295023D03*
X181921Y301920D03*
X191949Y301987D03*
X188810Y301998D03*
X187907Y308784D03*
X209449Y281098D03*
Y287398D03*
Y290548D03*
X203149Y287398D03*
X206299D03*
X196867Y294342D03*
X198880Y310245D03*
X196812Y308619D03*
X227517Y244187D03*
X225973Y265197D03*
X225160Y293676D03*
X225199Y290548D03*
Y284248D03*
X222049Y287398D03*
X212599D03*
X215749Y290548D03*
X225199Y306298D03*
Y312598D03*
X222049Y306298D03*
X218899D03*
X222049Y299998D03*
X212610Y306305D03*
X241613Y265197D03*
X233793Y266697D03*
Y257697D03*
X233904Y252772D03*
X234649Y281098D03*
X237865Y281131D03*
X231450Y290583D03*
X237760Y293692D03*
X237799Y287398D03*
X240949Y290548D03*
Y287398D03*
X231499Y284248D03*
Y296848D03*
Y293698D03*
Y299998D03*
X237799Y312598D03*
X231499D03*
X240949Y309448D03*
X259518Y252358D03*
X249433Y257697D03*
X246467Y255442D03*
X244099Y281098D03*
X254234Y281622D03*
X250399Y281098D03*
X244110Y290505D03*
X257447Y287117D03*
X244099Y287398D03*
X250399D03*
X253549Y290548D03*
X247249Y296848D03*
X244099D03*
X258590Y311560D03*
X253710Y315669D03*
X273660Y23037D03*
X273645Y27712D03*
X267268Y311642D03*
X264287Y311687D03*
X270518Y311637D03*
X268717Y606015D03*
X261967Y608638D03*
Y605638D03*
X260064Y602993D03*
X261967Y614638D03*
X263467Y626638D03*
X269428Y622966D03*
X261967Y617638D03*
X263467Y623638D03*
X273938Y633084D03*
X273674Y640095D03*
X273548Y636471D03*
X278305Y23057D03*
X278307Y27707D03*
X276386Y311687D03*
X310623Y313589D03*
X313123D03*
X320623D03*
X318123D03*
X315623D03*
X323123D03*
X401091Y587054D03*
X398386Y587126D03*
X401422Y597270D03*
Y599770D03*
X398822Y600399D03*
X406884Y594176D03*
X406881Y591322D03*
X412960Y618207D03*
X410315Y614782D03*
X436370Y410543D03*
X444020Y410374D03*
X439830D03*
X440900Y446260D03*
X436710D03*
X444850Y446337D03*
X640112Y285042D03*
X690986Y467975D03*
X687049Y479786D03*
X690986Y483723D03*
X687049Y471912D03*
X702797Y467975D03*
Y471912D03*
Y479786D03*
G54D33*
X414961Y98622D03*
X605796Y165160D03*
X609733Y215672D03*
G54D18*
X23628Y321764D03*
Y338300D03*
X45282Y321764D03*
Y338300D03*
X434102Y232640D03*
Y311875D03*
X583913Y69167D03*
X608571D03*
G54D23*
X76880Y143269D03*
X86880D03*
X739968Y29361D03*
X749968D03*
G54D27*
X151969Y98622D03*
G54D21*
X43898Y168544D03*
Y231457D03*
G54D42*
X711575Y143555D03*
Y195355D03*
Y222361D03*
Y274161D03*
X733975Y143555D03*
Y195355D03*
Y222361D03*
Y274161D03*
G54D17*
X25439Y303260D03*
Y356804D03*
G54D35*
X481102Y34528D03*
G54D41*
X688977Y105315D03*
Y719488D03*
G54D25*
X98426Y105512D03*
Y719685D03*
G54D26*
X102362Y247244D03*
Y349606D03*
X354331Y247244D03*
Y349606D03*
G54D34*
X413386Y377165D03*
G54D22*
X49830Y465496D03*
X47200Y467262D03*
X227816Y442675D03*
X218483Y442550D03*
X221858Y442300D03*
X225024Y442467D03*
X231885Y442252D03*
X318678Y540966D03*
X321828Y541682D03*
X324927Y546013D03*
X328592Y541146D03*
X328352Y545412D03*
X325588Y541447D03*
X323088Y561503D03*
X323188Y564503D03*
G54D14*
X-35858Y731383D03*
X28408Y26414D03*
X49559Y50577D03*
X51670Y462885D03*
X47590Y463876D03*
X49590Y469432D03*
X49185Y472713D03*
X64568Y451029D03*
X67568D03*
X70568D03*
X56330Y497940D03*
X58830D03*
X86050Y425112D03*
X85617Y451275D03*
X82617D03*
X88617D03*
X109972Y519508D03*
X126260Y470267D03*
X139310Y478102D03*
X136470Y481994D03*
X148140Y660112D03*
X148487Y676041D03*
X151915Y675068D03*
X155957Y674813D03*
X160112Y674990D03*
X165012Y675887D03*
X151567Y687579D03*
X155650Y681515D03*
X161994Y678445D03*
X159590Y683050D03*
X157287Y678138D03*
X165167Y681311D03*
X152222Y678394D03*
X160101Y687962D03*
X163018Y684381D03*
X164092Y688014D03*
X150840Y682436D03*
X168645Y688064D03*
X165628Y691289D03*
X167315Y684943D03*
X169268Y705304D03*
X169396Y701006D03*
X169268Y697399D03*
X169619Y693335D03*
X222290Y45504D03*
X226290D03*
X221310Y51103D03*
X225310D03*
X224730Y418003D03*
X221406Y436560D03*
X242290Y45504D03*
X230290D03*
X229310Y51103D03*
X233290Y51045D03*
X237310Y50983D03*
X241310D03*
X230749Y160807D03*
X230650Y164566D03*
X230890Y169424D03*
X231000Y173381D03*
X230100Y187389D03*
X230140Y197240D03*
X228906Y424560D03*
X228713Y416525D03*
Y419525D03*
X231870Y439511D03*
X228906Y433560D03*
Y427560D03*
Y436560D03*
X257270Y29334D03*
X258300Y22289D03*
X250290Y45504D03*
X246290D03*
X245310Y50867D03*
X249300Y50862D03*
X253490Y53736D03*
X250401Y315713D03*
X258798Y417594D03*
X254798Y417728D03*
X271421Y7319D03*
X268579Y19365D03*
X265934Y16522D03*
X274580Y74281D03*
X269920Y74318D03*
X272440Y76177D03*
X268080Y76416D03*
X268702Y107928D03*
X280699Y13908D03*
X278199D03*
X282180Y10253D03*
X285703Y9813D03*
X280699Y16408D03*
X278199D03*
X277472Y34959D03*
Y37459D03*
X280072Y34330D03*
X287270Y75018D03*
X283870Y74724D03*
X279100Y74447D03*
X289738Y76173D03*
X285543Y76867D03*
X281400Y75938D03*
X276969Y76247D03*
X287599Y108831D03*
X278880Y108482D03*
X280730Y393856D03*
X292313Y76345D03*
X305880Y76361D03*
X299220Y76196D03*
X302953Y76167D03*
X295867Y76567D03*
X299590Y121289D03*
X299850Y124708D03*
X318910Y74595D03*
X314310Y74540D03*
X307740Y74263D03*
X309730Y76232D03*
X321283Y76327D03*
X316623Y76047D03*
X312402Y76587D03*
X313583Y122387D03*
X321144Y399643D03*
X318644D03*
X323640Y74393D03*
X326140Y76196D03*
X323032Y122237D03*
X326282Y399743D03*
X323644Y399643D03*
X328290Y424304D03*
X334420Y428660D03*
X346020Y374075D03*
X341011Y537828D03*
X357820Y534561D03*
X383617Y517862D03*
X383034Y640267D03*
X400589Y611672D03*
X400587Y607022D03*
X398195Y620821D03*
X400695Y618321D03*
X398195D03*
X400695Y620821D03*
X392063Y624109D03*
X395701Y637430D03*
X399440Y637340D03*
X405970Y256489D03*
X409251Y521763D03*
X405234Y611692D03*
X405249Y607017D03*
X405426Y626809D03*
X409520Y637387D03*
X414760Y636225D03*
X426068Y546048D03*
X417979Y545352D03*
X422210Y605343D03*
X419221Y612253D03*
X425151Y608429D03*
X420245Y636004D03*
X417422Y637592D03*
X440040Y608537D03*
X439250Y630973D03*
X461516Y78275D03*
X459990Y245930D03*
X471795Y267941D03*
X473294Y613207D03*
X494340Y691623D03*
X496955Y99958D03*
X508955Y99978D03*
X500955Y100139D03*
X504955Y99830D03*
X512955Y100428D03*
X524955Y99359D03*
X516955Y100333D03*
X520955Y100444D03*
X528955Y99781D03*
X532955Y100604D03*
X596560Y536108D03*
X622798Y546764D03*
X651395Y487265D03*
X641842Y516730D03*
X684620Y535923D03*
X678217Y536752D03*
X686661Y519199D03*
X698438Y524890D03*
X694150Y536155D03*
X690040Y535797D03*
X687183Y539585D03*
X707736Y510140D03*
X712820Y519647D03*
X708258Y549815D03*
X758494Y455532D03*
G54D30*
X230476Y508891D03*
X239925Y527788D03*
Y524639D03*
X249374Y512040D03*
X246224D03*
X249374Y549835D03*
X265122Y512040D03*
X261972D03*
X265122Y549836D03*
X261972D03*
X277725Y521493D03*
%LPC*%
G75*
G36*
G01X-36897Y131113D02*
G02X-34847I1025J-400D01*
G01X-33897D01*
G02Y130313I1025J-400D01*
G01X-34847D01*
G02X-36897I-1025J400D01*
G01X-37847D01*
G02Y131113I-1025J400D01*
G01X-36897D01*
G37*
G36*
G01Y238433D02*
G02X-34847I1025J-400D01*
G01X-33897D01*
G02Y237633I1025J-400D01*
G01X-34847D01*
G02X-36897I-1025J400D01*
G01X-37847D01*
G02Y238433I-1025J400D01*
G01X-36897D01*
G37*
G36*
G01X-34847D02*
G03X-36897I-1025J-400D01*
G01X-37847D01*
G03Y237633I-1025J-400D01*
G01X-36897D01*
G03X-34847I1025J400D01*
G01X-33897D01*
G03Y238433I1025J400D01*
G01X-34847D01*
G37*
G36*
G01Y748593D02*
G02X-36897I-1025J400D01*
G01X-37847D01*
G02Y749393I-1025J400D01*
G01X-36897D01*
G02X-34847I1025J-400D01*
G01X-33897D01*
G02Y748593I1025J-400D01*
G01X-34847D01*
G37*
G54D43*
G01X38493Y-241864D02*
Y-246864D01*
G01X37036Y-241864D02*
X39950D01*
G01X44860Y-246864D02*
X42326D01*
Y-241864D01*
X44860D01*
G01X43846Y-244281D02*
X42326D01*
G01X47426Y-241864D02*
Y-246864D01*
X49960D01*
G01X53793Y-247031D02*
X53666Y-246947D01*
Y-246781D01*
X53793Y-246697D01*
X53920Y-246781D01*
Y-246947D01*
X53793Y-247031D01*
G01Y-244781D02*
X53666Y-244697D01*
Y-244531D01*
X53793Y-244447D01*
X53920Y-244531D01*
Y-244697D01*
X53793Y-244781D01*
G01X58576Y-248531D02*
X57943Y-247697D01*
X57626Y-246864D01*
Y-243531D01*
X57943Y-242697D01*
X58576Y-241864D01*
G01X63993D02*
X63486Y-242031D01*
X63106Y-242447D01*
X62853Y-242947D01*
X62663Y-243614D01*
X62600Y-244364D01*
X62663Y-245114D01*
X62853Y-245781D01*
X63106Y-246281D01*
X63486Y-246697D01*
X63993Y-246864D01*
X64500Y-246697D01*
X64880Y-246281D01*
X65133Y-245781D01*
X65323Y-245114D01*
X65386Y-244364D01*
X65323Y-243614D01*
X65133Y-242947D01*
X64880Y-242447D01*
X64500Y-242031D01*
X63993Y-241864D01*
G01X67700Y-245864D02*
X68080Y-246447D01*
X68586Y-246781D01*
X69156Y-246864D01*
X69663Y-246781D01*
X70170Y-246364D01*
X70486Y-245864D01*
X70550Y-245364D01*
X70423Y-244781D01*
X69980Y-244364D01*
X69536Y-244197D01*
X68966D01*
G01X69536D02*
X69916Y-243947D01*
X70233Y-243531D01*
X70360Y-243031D01*
X70233Y-242531D01*
X69916Y-242114D01*
X69346Y-241864D01*
X68776Y-241947D01*
X68206Y-242281D01*
G01X74510Y-248531D02*
X75143Y-247697D01*
X75460Y-246864D01*
Y-243531D01*
X75143Y-242697D01*
X74510Y-241864D01*
G01X77900Y-245864D02*
X78280Y-246447D01*
X78786Y-246781D01*
X79356Y-246864D01*
X79863Y-246781D01*
X80370Y-246364D01*
X80686Y-245864D01*
X80750Y-245364D01*
X80623Y-244781D01*
X80180Y-244364D01*
X79736Y-244197D01*
X79166D01*
G01X79736D02*
X80116Y-243947D01*
X80433Y-243531D01*
X80560Y-243031D01*
X80433Y-242531D01*
X80116Y-242114D01*
X79546Y-241864D01*
X78976Y-241947D01*
X78406Y-242281D01*
G01X83190Y-242697D02*
X83570Y-242197D01*
X84013Y-241947D01*
X84520Y-241864D01*
X85153Y-242031D01*
X85596Y-242447D01*
X85723Y-242947D01*
X85660Y-243447D01*
X85406Y-243864D01*
X84140Y-244697D01*
X83570Y-245281D01*
X83190Y-246114D01*
X83063Y-246864D01*
X85723D01*
G01X89366D02*
X89493Y-245781D01*
X89683Y-244864D01*
X89936Y-244031D01*
X90253Y-243114D01*
X90760Y-241864D01*
X88226D01*
G01X93770Y-245197D02*
X95416D01*
G01X98490Y-242697D02*
X98870Y-242197D01*
X99313Y-241947D01*
X99820Y-241864D01*
X100453Y-242031D01*
X100896Y-242447D01*
X101023Y-242947D01*
X100960Y-243447D01*
X100706Y-243864D01*
X99440Y-244697D01*
X98870Y-245281D01*
X98490Y-246114D01*
X98363Y-246864D01*
X101023D01*
G01X103400Y-245864D02*
X103780Y-246447D01*
X104286Y-246781D01*
X104856Y-246864D01*
X105363Y-246781D01*
X105870Y-246364D01*
X106186Y-245864D01*
X106250Y-245364D01*
X106123Y-244781D01*
X105680Y-244364D01*
X105236Y-244197D01*
X104666D01*
G01X105236D02*
X105616Y-243947D01*
X105933Y-243531D01*
X106060Y-243031D01*
X105933Y-242531D01*
X105616Y-242114D01*
X105046Y-241864D01*
X104476Y-241947D01*
X103906Y-242281D01*
G01X110653Y-246864D02*
Y-241864D01*
X108310Y-245447D01*
X111476D01*
G01X113600Y-246114D02*
X113980Y-246531D01*
X114423Y-246781D01*
X114993Y-246864D01*
X115563Y-246697D01*
X116006Y-246364D01*
X116323Y-245781D01*
X116386Y-245114D01*
X116260Y-244447D01*
X115943Y-244031D01*
X115500Y-243697D01*
X115056Y-243614D01*
X114613Y-243697D01*
X114043Y-244031D01*
X114233Y-241864D01*
X115943D01*
G01X123990Y-246864D02*
Y-241864D01*
X126396D01*
G01X125510Y-244281D02*
X123990D01*
G01X128710Y-246864D02*
X130293Y-241864D01*
X131876Y-246864D01*
G01X131306Y-245114D02*
X129280D01*
G01X134063Y-246864D02*
X136723Y-241864D01*
G01X134063D02*
X136723Y-246864D01*
G01X140493Y-247031D02*
X140366Y-246947D01*
Y-246781D01*
X140493Y-246697D01*
X140620Y-246781D01*
Y-246947D01*
X140493Y-247031D01*
G01Y-244781D02*
X140366Y-244697D01*
Y-244531D01*
X140493Y-244447D01*
X140620Y-244531D01*
Y-244697D01*
X140493Y-244781D01*
G01X145276Y-248531D02*
X144643Y-247697D01*
X144326Y-246864D01*
Y-243531D01*
X144643Y-242697D01*
X145276Y-241864D01*
G01X150693D02*
X150186Y-242031D01*
X149806Y-242447D01*
X149553Y-242947D01*
X149363Y-243614D01*
X149300Y-244364D01*
X149363Y-245114D01*
X149553Y-245781D01*
X149806Y-246281D01*
X150186Y-246697D01*
X150693Y-246864D01*
X151200Y-246697D01*
X151580Y-246281D01*
X151833Y-245781D01*
X152023Y-245114D01*
X152086Y-244364D01*
X152023Y-243614D01*
X151833Y-242947D01*
X151580Y-242447D01*
X151200Y-242031D01*
X150693Y-241864D01*
G01X154400Y-245864D02*
X154780Y-246447D01*
X155286Y-246781D01*
X155856Y-246864D01*
X156363Y-246781D01*
X156870Y-246364D01*
X157186Y-245864D01*
X157250Y-245364D01*
X157123Y-244781D01*
X156680Y-244364D01*
X156236Y-244197D01*
X155666D01*
G01X156236D02*
X156616Y-243947D01*
X156933Y-243531D01*
X157060Y-243031D01*
X156933Y-242531D01*
X156616Y-242114D01*
X156046Y-241864D01*
X155476Y-241947D01*
X154906Y-242281D01*
G01X161210Y-248531D02*
X161843Y-247697D01*
X162160Y-246864D01*
Y-243531D01*
X161843Y-242697D01*
X161210Y-241864D01*
G01X164600Y-245864D02*
X164980Y-246447D01*
X165486Y-246781D01*
X166056Y-246864D01*
X166563Y-246781D01*
X167070Y-246364D01*
X167386Y-245864D01*
X167450Y-245364D01*
X167323Y-244781D01*
X166880Y-244364D01*
X166436Y-244197D01*
X165866D01*
G01X166436D02*
X166816Y-243947D01*
X167133Y-243531D01*
X167260Y-243031D01*
X167133Y-242531D01*
X166816Y-242114D01*
X166246Y-241864D01*
X165676Y-241947D01*
X165106Y-242281D01*
G01X170016Y-246281D02*
X170460Y-246697D01*
X170966Y-246864D01*
X171473Y-246697D01*
X171916Y-246197D01*
X172233Y-245447D01*
X172360Y-244697D01*
Y-243781D01*
X172233Y-243031D01*
X171916Y-242364D01*
X171536Y-242031D01*
X171093Y-241864D01*
X170586Y-242031D01*
X170206Y-242364D01*
X169953Y-242864D01*
X169826Y-243531D01*
X169953Y-244114D01*
X170270Y-244697D01*
X170650Y-245031D01*
X171093Y-245114D01*
X171600Y-244947D01*
X171980Y-244531D01*
X172360Y-243781D01*
G01X176066Y-246864D02*
X176193Y-245781D01*
X176383Y-244864D01*
X176636Y-244031D01*
X176953Y-243114D01*
X177460Y-241864D01*
X174926D01*
G01X180470Y-245197D02*
X182116D01*
G01X185000Y-245864D02*
X185380Y-246447D01*
X185886Y-246781D01*
X186456Y-246864D01*
X186963Y-246781D01*
X187470Y-246364D01*
X187786Y-245864D01*
X187850Y-245364D01*
X187723Y-244781D01*
X187280Y-244364D01*
X186836Y-244197D01*
X186266D01*
G01X186836D02*
X187216Y-243947D01*
X187533Y-243531D01*
X187660Y-243031D01*
X187533Y-242531D01*
X187216Y-242114D01*
X186646Y-241864D01*
X186076Y-241947D01*
X185506Y-242281D01*
G01X190290Y-244781D02*
X190733Y-244197D01*
X191113Y-243864D01*
X191620Y-243697D01*
X192063Y-243864D01*
X192380Y-244197D01*
X192633Y-244697D01*
X192696Y-245281D01*
X192633Y-245781D01*
X192380Y-246281D01*
X192000Y-246697D01*
X191556Y-246864D01*
X191050Y-246697D01*
X190606Y-246197D01*
X190353Y-245447D01*
X190290Y-244614D01*
X190416Y-243531D01*
X190606Y-242947D01*
X190923Y-242364D01*
X191366Y-241947D01*
X191810Y-241864D01*
X192253Y-242031D01*
X192570Y-242447D01*
G01X196593Y-246864D02*
Y-241864D01*
X195833Y-242864D01*
G01Y-246864D02*
X197353D01*
G01X202453D02*
Y-241864D01*
X200110Y-245447D01*
X203276D01*
G01X26493Y-176864D02*
Y-251864D01*
X526493D01*
Y-176864D01*
X26493D01*
G01X221493D02*
Y-251864D01*
G01Y-226864D02*
X324493D01*
Y-201864D01*
G01X221493D02*
X324493D01*
G01X332000Y-236864D02*
Y-231864D01*
X333266D01*
X333773Y-232114D01*
X334153Y-232447D01*
X334470Y-232947D01*
X334723Y-233531D01*
X334786Y-234364D01*
X334723Y-235197D01*
X334470Y-235781D01*
X334153Y-236281D01*
X333773Y-236614D01*
X333266Y-236864D01*
X332000D01*
G01X336910D02*
X338493Y-231864D01*
X340076Y-236864D01*
G01X339506Y-235114D02*
X337480D01*
G01X343593Y-231864D02*
Y-236864D01*
G01X342136Y-231864D02*
X345050D01*
G01X349960Y-236864D02*
X347426D01*
Y-231864D01*
X349960D01*
G01X348946Y-234281D02*
X347426D01*
G01X353793Y-237031D02*
X353666Y-236947D01*
Y-236781D01*
X353793Y-236697D01*
X353920Y-236781D01*
Y-236947D01*
X353793Y-237031D01*
G01Y-234781D02*
X353666Y-234697D01*
Y-234531D01*
X353793Y-234447D01*
X353920Y-234531D01*
Y-234697D01*
X353793Y-234781D01*
G01X326493Y-176864D02*
Y-251864D01*
G01X324493Y-176864D02*
Y-251864D01*
G01X326493Y-226864D02*
X526493D01*
G01X332126Y-211864D02*
Y-206864D01*
X333646D01*
X334153Y-207114D01*
X334533Y-207697D01*
X334660Y-208364D01*
X334533Y-209031D01*
X334216Y-209531D01*
X333646Y-209781D01*
X332126D01*
G01X337353Y-212031D02*
X339633Y-206864D01*
G01X342136Y-211864D02*
Y-206864D01*
X345050Y-211864D01*
Y-206864D01*
G01X348693Y-212031D02*
X348566Y-211947D01*
Y-211781D01*
X348693Y-211697D01*
X348820Y-211781D01*
Y-211947D01*
X348693Y-212031D01*
G01Y-209781D02*
X348566Y-209697D01*
Y-209531D01*
X348693Y-209447D01*
X348820Y-209531D01*
Y-209697D01*
X348693Y-209781D01*
G01X326493Y-201864D02*
X526493D01*
G01X332126Y-186864D02*
Y-181864D01*
X333646D01*
X334153Y-182114D01*
X334533Y-182697D01*
X334660Y-183364D01*
X334533Y-184031D01*
X334216Y-184531D01*
X333646Y-184781D01*
X332126D01*
G01X337226Y-186864D02*
Y-181864D01*
X338810D01*
X339316Y-182114D01*
X339633Y-182447D01*
X339760Y-183114D01*
X339633Y-183781D01*
X339253Y-184197D01*
X338810Y-184447D01*
X337226D01*
G01X338810D02*
X339760Y-186864D01*
G01X343593D02*
X343086Y-186781D01*
X342643Y-186447D01*
X342263Y-185947D01*
X342010Y-185364D01*
X341883Y-184697D01*
Y-184031D01*
X342010Y-183364D01*
X342263Y-182781D01*
X342643Y-182281D01*
X343086Y-181947D01*
X343593Y-181864D01*
X344100Y-181947D01*
X344543Y-182281D01*
X344923Y-182781D01*
X345176Y-183364D01*
X345303Y-184031D01*
Y-184697D01*
X345176Y-185364D01*
X344923Y-185947D01*
X344543Y-186447D01*
X344100Y-186781D01*
X343593Y-186864D01*
G01X347426Y-185864D02*
X347743Y-186364D01*
X348123Y-186697D01*
X348566Y-186864D01*
X349073Y-186697D01*
X349453Y-186364D01*
X349833Y-185864D01*
X349960Y-185197D01*
Y-181864D01*
G01X355060Y-186864D02*
X352526D01*
Y-181864D01*
X355060D01*
G01X354046Y-184281D02*
X352526D01*
G01X360286Y-182281D02*
X359906Y-182031D01*
X359463Y-181864D01*
X358956D01*
X358386Y-182114D01*
X357943Y-182531D01*
X357626Y-183031D01*
X357373Y-183864D01*
X357310Y-184614D01*
X357436Y-185364D01*
X357626Y-185864D01*
X358006Y-186364D01*
X358450Y-186697D01*
X358893Y-186864D01*
X359336D01*
X359780Y-186697D01*
X360160Y-186447D01*
X360476Y-186114D01*
G01X363993Y-181864D02*
Y-186864D01*
G01X362536Y-181864D02*
X365450D01*
G01X369093Y-187031D02*
X368966Y-186947D01*
Y-186781D01*
X369093Y-186697D01*
X369220Y-186781D01*
Y-186947D01*
X369093Y-187031D01*
G01Y-184781D02*
X368966Y-184697D01*
Y-184531D01*
X369093Y-184447D01*
X369220Y-184531D01*
Y-184697D01*
X369093Y-184781D01*
G01X447126Y-236864D02*
Y-231864D01*
X448710D01*
X449216Y-232114D01*
X449533Y-232447D01*
X449660Y-233114D01*
X449533Y-233781D01*
X449153Y-234197D01*
X448710Y-234447D01*
X447126D01*
G01X448710D02*
X449660Y-236864D01*
G01X454760D02*
X452226D01*
Y-231864D01*
X454760D01*
G01X453746Y-234281D02*
X452226D01*
G01X457010Y-231864D02*
X458593Y-236864D01*
X460176Y-231864D01*
G01X463693Y-237031D02*
X463566Y-236947D01*
Y-236781D01*
X463693Y-236697D01*
X463820Y-236781D01*
Y-236947D01*
X463693Y-237031D01*
G01Y-234781D02*
X463566Y-234697D01*
Y-234531D01*
X463693Y-234447D01*
X463820Y-234531D01*
Y-234697D01*
X463693Y-234781D01*
G01X441493Y-226864D02*
Y-251864D01*
G01X490493Y-226864D02*
Y-251864D01*
G01X-1043962Y-705877D02*
Y2342823D01*
X2300638D01*
Y-705877D01*
X-1043962D01*
G01X37198Y-238524D02*
X37825Y-239049D01*
X38530Y-239364D01*
X39156D01*
X39783Y-239049D01*
X40253Y-238524D01*
X40488Y-237789D01*
X40331Y-237054D01*
X39940Y-236424D01*
X39235Y-236004D01*
X38295Y-235794D01*
X37746Y-235374D01*
X37511Y-234639D01*
X37668Y-233904D01*
X38060Y-233379D01*
X38608Y-233064D01*
X39156D01*
X39705Y-233274D01*
X40175Y-233799D01*
G01X43498Y-239364D02*
Y-233064D01*
G01X46788D02*
Y-239364D01*
G01Y-236214D02*
X43498D01*
G01X50503Y-233064D02*
X52383D01*
G01X51443D02*
Y-239364D01*
G01X50503D02*
X52383D01*
G01X59310D02*
X56176D01*
Y-233064D01*
X59310D01*
G01X58056Y-236109D02*
X56176D01*
G01X62241Y-239364D02*
Y-233064D01*
X65845Y-239364D01*
Y-233064D01*
G01X70186Y-240519D02*
X70500Y-239154D01*
G01X76643Y-233064D02*
Y-239364D01*
G01X74841Y-233064D02*
X78445D01*
G01X80985Y-239364D02*
X82943Y-233064D01*
X84901Y-239364D01*
G01X84196Y-237159D02*
X81690D01*
G01X88303Y-233064D02*
X90183D01*
G01X89243D02*
Y-239364D01*
G01X88303D02*
X90183D01*
G01X93193Y-233064D02*
X94290Y-239364D01*
X95543Y-233064D01*
X96796Y-239364D01*
X97893Y-233064D01*
G01X99885Y-239364D02*
X101843Y-233064D01*
X103801Y-239364D01*
G01X103096Y-237159D02*
X100590D01*
G01X106341Y-239364D02*
Y-233064D01*
X109945Y-239364D01*
Y-233064D01*
G01X119176Y-239364D02*
Y-233064D01*
X121135D01*
X121761Y-233379D01*
X122153Y-233799D01*
X122310Y-234639D01*
X122153Y-235479D01*
X121683Y-236004D01*
X121135Y-236319D01*
X119176D01*
G01X121135D02*
X122310Y-239364D01*
G01X127043Y-239574D02*
X126886Y-239469D01*
Y-239259D01*
X127043Y-239154D01*
X127200Y-239259D01*
Y-239469D01*
X127043Y-239574D01*
G01X133343Y-239364D02*
X132716Y-239259D01*
X132168Y-238839D01*
X131698Y-238209D01*
X131385Y-237474D01*
X131228Y-236634D01*
Y-235794D01*
X131385Y-234954D01*
X131698Y-234219D01*
X132168Y-233589D01*
X132716Y-233169D01*
X133343Y-233064D01*
X133970Y-233169D01*
X134518Y-233589D01*
X134988Y-234219D01*
X135301Y-234954D01*
X135458Y-235794D01*
Y-236634D01*
X135301Y-237474D01*
X134988Y-238209D01*
X134518Y-238839D01*
X133970Y-239259D01*
X133343Y-239364D01*
G01X139643Y-239574D02*
X139486Y-239469D01*
Y-239259D01*
X139643Y-239154D01*
X139800Y-239259D01*
Y-239469D01*
X139643Y-239574D01*
G01X147666Y-233589D02*
X147196Y-233274D01*
X146648Y-233064D01*
X146021D01*
X145316Y-233379D01*
X144768Y-233904D01*
X144376Y-234534D01*
X144063Y-235584D01*
X143985Y-236529D01*
X144141Y-237474D01*
X144376Y-238104D01*
X144846Y-238734D01*
X145395Y-239154D01*
X145943Y-239364D01*
X146491D01*
X147040Y-239154D01*
X147510Y-238839D01*
X147901Y-238419D01*
G01X152243Y-239574D02*
X152086Y-239469D01*
Y-239259D01*
X152243Y-239154D01*
X152400Y-239259D01*
Y-239469D01*
X152243Y-239574D01*
G01X37120Y-229364D02*
Y-223064D01*
G01X40096D02*
X37120Y-226949D01*
G01X40566Y-229364D02*
X38451Y-225164D01*
G01X43420Y-223064D02*
Y-227579D01*
X43733Y-228524D01*
X44360Y-229154D01*
X45143Y-229364D01*
X45926Y-229154D01*
X46553Y-228524D01*
X46866Y-227579D01*
Y-223064D01*
G01X53010Y-229364D02*
X49876D01*
Y-223064D01*
X53010D01*
G01X51756Y-226109D02*
X49876D01*
G01X56803Y-223064D02*
X58683D01*
G01X57743D02*
Y-229364D01*
G01X56803D02*
X58683D01*
G01X68698Y-228524D02*
X69325Y-229049D01*
X70030Y-229364D01*
X70656D01*
X71283Y-229049D01*
X71753Y-228524D01*
X71988Y-227789D01*
X71831Y-227054D01*
X71440Y-226424D01*
X70735Y-226004D01*
X69795Y-225794D01*
X69246Y-225374D01*
X69011Y-224639D01*
X69168Y-223904D01*
X69560Y-223379D01*
X70108Y-223064D01*
X70656D01*
X71205Y-223274D01*
X71675Y-223799D01*
G01X74998Y-229364D02*
Y-223064D01*
G01X78288D02*
Y-229364D01*
G01Y-226214D02*
X74998D01*
G01X80985Y-229364D02*
X82943Y-223064D01*
X84901Y-229364D01*
G01X84196Y-227159D02*
X81690D01*
G01X87441Y-229364D02*
Y-223064D01*
X91045Y-229364D01*
Y-223064D01*
G01X100198Y-229364D02*
Y-223064D01*
G01X103488D02*
Y-229364D01*
G01Y-226214D02*
X100198D01*
G01X106498Y-228524D02*
X107125Y-229049D01*
X107830Y-229364D01*
X108456D01*
X109083Y-229049D01*
X109553Y-228524D01*
X109788Y-227789D01*
X109631Y-227054D01*
X109240Y-226424D01*
X108535Y-226004D01*
X107595Y-225794D01*
X107046Y-225374D01*
X106811Y-224639D01*
X106968Y-223904D01*
X107360Y-223379D01*
X107908Y-223064D01*
X108456D01*
X109005Y-223274D01*
X109475Y-223799D01*
G01X113503Y-223064D02*
X115383D01*
G01X114443D02*
Y-229364D01*
G01X113503D02*
X115383D01*
G01X118785D02*
X120743Y-223064D01*
X122701Y-229364D01*
G01X121996Y-227159D02*
X119490D01*
G01X125241Y-229364D02*
Y-223064D01*
X128845Y-229364D01*
Y-223064D01*
G01X133813Y-226214D02*
X135380D01*
Y-228104D01*
X134910Y-228734D01*
X134361Y-229154D01*
X133578Y-229364D01*
X132795Y-229154D01*
X132246Y-228734D01*
X131776Y-228104D01*
X131463Y-227369D01*
X131306Y-226529D01*
Y-225794D01*
X131463Y-225164D01*
X131776Y-224429D01*
X132246Y-223799D01*
X132716Y-223379D01*
X133343Y-223064D01*
X133891D01*
X134518Y-223274D01*
X134988Y-223694D01*
G01X139486Y-230519D02*
X139800Y-229154D01*
G01X145943Y-223064D02*
Y-229364D01*
G01X144141Y-223064D02*
X147745D01*
G01X150285Y-229364D02*
X152243Y-223064D01*
X154201Y-229364D01*
G01X153496Y-227159D02*
X150990D01*
G01X158543Y-229364D02*
X157916Y-229259D01*
X157368Y-228839D01*
X156898Y-228209D01*
X156585Y-227474D01*
X156428Y-226634D01*
Y-225794D01*
X156585Y-224954D01*
X156898Y-224219D01*
X157368Y-223589D01*
X157916Y-223169D01*
X158543Y-223064D01*
X159170Y-223169D01*
X159718Y-223589D01*
X160188Y-224219D01*
X160501Y-224954D01*
X160658Y-225794D01*
Y-226634D01*
X160501Y-227474D01*
X160188Y-228209D01*
X159718Y-228839D01*
X159170Y-229259D01*
X158543Y-229364D01*
G01X171143D02*
Y-226529D01*
X169576Y-223064D01*
G01X172710D02*
X171143Y-226529D01*
G01X175720Y-223064D02*
Y-227579D01*
X176033Y-228524D01*
X176660Y-229154D01*
X177443Y-229364D01*
X178226Y-229154D01*
X178853Y-228524D01*
X179166Y-227579D01*
Y-223064D01*
G01X181785Y-229364D02*
X183743Y-223064D01*
X185701Y-229364D01*
G01X184996Y-227159D02*
X182490D01*
G01X188241Y-229364D02*
Y-223064D01*
X191845Y-229364D01*
Y-223064D01*
G01X37041Y-219364D02*
Y-213064D01*
X40645Y-219364D01*
Y-213064D01*
G01X45143Y-219364D02*
X44516Y-219259D01*
X43968Y-218839D01*
X43498Y-218209D01*
X43185Y-217474D01*
X43028Y-216634D01*
Y-215794D01*
X43185Y-214954D01*
X43498Y-214219D01*
X43968Y-213589D01*
X44516Y-213169D01*
X45143Y-213064D01*
X45770Y-213169D01*
X46318Y-213589D01*
X46788Y-214219D01*
X47101Y-214954D01*
X47258Y-215794D01*
Y-216634D01*
X47101Y-217474D01*
X46788Y-218209D01*
X46318Y-218839D01*
X45770Y-219259D01*
X45143Y-219364D01*
G01X51443Y-219574D02*
X51286Y-219469D01*
Y-219259D01*
X51443Y-219154D01*
X51600Y-219259D01*
Y-219469D01*
X51443Y-219574D01*
G01X57743Y-219364D02*
Y-213064D01*
X56803Y-214324D01*
G01Y-219364D02*
X58683D01*
G01X64043D02*
X64591Y-219259D01*
X65218Y-218944D01*
X65610Y-218419D01*
X65766Y-217684D01*
X65610Y-216949D01*
X65140Y-216319D01*
X64435Y-216004D01*
X63651D01*
X63181Y-215794D01*
X62790Y-215269D01*
X62633Y-214534D01*
X62868Y-213799D01*
X63416Y-213274D01*
X64043Y-213064D01*
X64670Y-213274D01*
X65218Y-213799D01*
X65453Y-214534D01*
X65296Y-215269D01*
X64905Y-215794D01*
X64435Y-216004D01*
X63651D01*
X62946Y-216319D01*
X62476Y-216949D01*
X62320Y-217684D01*
X62476Y-218419D01*
X62868Y-218944D01*
X63495Y-219259D01*
X64043Y-219364D01*
G01X70343D02*
X70891Y-219259D01*
X71518Y-218944D01*
X71910Y-218419D01*
X72066Y-217684D01*
X71910Y-216949D01*
X71440Y-216319D01*
X70735Y-216004D01*
X69951D01*
X69481Y-215794D01*
X69090Y-215269D01*
X68933Y-214534D01*
X69168Y-213799D01*
X69716Y-213274D01*
X70343Y-213064D01*
X70970Y-213274D01*
X71518Y-213799D01*
X71753Y-214534D01*
X71596Y-215269D01*
X71205Y-215794D01*
X70735Y-216004D01*
X69951D01*
X69246Y-216319D01*
X68776Y-216949D01*
X68620Y-217684D01*
X68776Y-218419D01*
X69168Y-218944D01*
X69795Y-219259D01*
X70343Y-219364D01*
G01X76486Y-220519D02*
X76800Y-219154D01*
G01X80593Y-213064D02*
X81690Y-219364D01*
X82943Y-213064D01*
X84196Y-219364D01*
X85293Y-213064D01*
G01X90810Y-219364D02*
X87676D01*
Y-213064D01*
X90810D01*
G01X89556Y-216109D02*
X87676D01*
G01X93741Y-219364D02*
Y-213064D01*
X97345Y-219364D01*
Y-213064D01*
G01X106498Y-219364D02*
Y-213064D01*
G01X109788D02*
Y-219364D01*
G01Y-216214D02*
X106498D01*
G01X112093Y-213064D02*
X113190Y-219364D01*
X114443Y-213064D01*
X115696Y-219364D01*
X116793Y-213064D01*
G01X118785Y-219364D02*
X120743Y-213064D01*
X122701Y-219364D01*
G01X121996Y-217159D02*
X119490D01*
G01X131855Y-214114D02*
X132325Y-213484D01*
X132873Y-213169D01*
X133500Y-213064D01*
X134283Y-213274D01*
X134831Y-213799D01*
X134988Y-214429D01*
X134910Y-215059D01*
X134596Y-215584D01*
X133030Y-216634D01*
X132325Y-217369D01*
X131855Y-218419D01*
X131698Y-219364D01*
X134988D01*
G01X137841D02*
Y-213064D01*
X141445Y-219364D01*
Y-213064D01*
G01X144220Y-219364D02*
Y-213064D01*
X145786D01*
X146413Y-213379D01*
X146883Y-213799D01*
X147275Y-214429D01*
X147588Y-215164D01*
X147666Y-216214D01*
X147588Y-217264D01*
X147275Y-217999D01*
X146883Y-218629D01*
X146413Y-219049D01*
X145786Y-219364D01*
X144220D01*
G01X156976D02*
Y-213064D01*
X158935D01*
X159561Y-213379D01*
X159953Y-213799D01*
X160110Y-214639D01*
X159953Y-215479D01*
X159483Y-216004D01*
X158935Y-216319D01*
X156976D01*
G01X158935D02*
X160110Y-219364D01*
G01X163120D02*
Y-213064D01*
X164686D01*
X165313Y-213379D01*
X165783Y-213799D01*
X166175Y-214429D01*
X166488Y-215164D01*
X166566Y-216214D01*
X166488Y-217264D01*
X166175Y-217999D01*
X165783Y-218629D01*
X165313Y-219049D01*
X164686Y-219364D01*
X163120D01*
G01X171143Y-219574D02*
X170986Y-219469D01*
Y-219259D01*
X171143Y-219154D01*
X171300Y-219259D01*
Y-219469D01*
X171143Y-219574D01*
G01X61143Y-206664D02*
X58623Y-206247D01*
X56418Y-204581D01*
X54528Y-202081D01*
X53268Y-199164D01*
X52638Y-195831D01*
Y-192497D01*
X53268Y-189164D01*
X54528Y-186247D01*
X56418Y-183748D01*
X58623Y-182081D01*
X61143Y-181664D01*
X63663Y-182081D01*
X65868Y-183748D01*
X67758Y-186247D01*
X69018Y-189164D01*
X69648Y-192497D01*
Y-195831D01*
X69018Y-199164D01*
X67758Y-202081D01*
X65868Y-204581D01*
X63663Y-206247D01*
X61143Y-206664D01*
G01X63663Y-199997D02*
X67443Y-206664D01*
G01X80988Y-189998D02*
Y-201664D01*
X82248Y-204581D01*
X84138Y-206247D01*
X86343Y-206664D01*
X88548Y-206247D01*
X90438Y-204581D01*
X91698Y-201664D01*
G01Y-206664D02*
Y-189998D01*
G01X117213Y-206664D02*
Y-189998D01*
G01Y-192914D02*
X115953Y-191248D01*
X114063Y-190414D01*
X111858Y-189998D01*
X109653Y-190831D01*
X107763Y-192497D01*
X106503Y-194998D01*
X105873Y-198331D01*
X106503Y-201664D01*
X107763Y-204165D01*
X109653Y-205831D01*
X111858Y-206664D01*
X114063Y-206247D01*
X115953Y-204998D01*
X117213Y-203331D01*
G01X131388Y-206664D02*
Y-189998D01*
G01Y-194164D02*
X132648Y-192081D01*
X134538Y-190414D01*
X137058Y-189998D01*
X139263Y-190414D01*
X141153Y-192081D01*
X142098Y-194998D01*
Y-206664D01*
G01X161943Y-181664D02*
Y-206664D01*
G01X157533Y-189998D02*
X166353D01*
G01X192813Y-206664D02*
Y-189998D01*
G01Y-192914D02*
X191553Y-191248D01*
X189663Y-190414D01*
X187458Y-189998D01*
X185253Y-190831D01*
X183363Y-192497D01*
X182103Y-194998D01*
X181473Y-198331D01*
X182103Y-201664D01*
X183363Y-204165D01*
X185253Y-205831D01*
X187458Y-206664D01*
X189663Y-206247D01*
X191553Y-204998D01*
X192813Y-203331D01*
G01X232493Y-186364D02*
Y-194364D01*
X236493D01*
G01X244293D02*
Y-189031D01*
G01Y-189964D02*
X243893Y-189431D01*
X243293Y-189164D01*
X242593Y-189031D01*
X241893Y-189297D01*
X241293Y-189831D01*
X240893Y-190631D01*
X240693Y-191697D01*
X240893Y-192764D01*
X241293Y-193564D01*
X241893Y-194097D01*
X242593Y-194364D01*
X243293Y-194231D01*
X243893Y-193831D01*
X244293Y-193298D01*
G01X248393Y-196764D02*
X248993Y-197031D01*
X249793Y-196764D01*
X250293Y-196231D01*
X250693Y-195564D01*
X251293Y-193431D01*
X252593Y-189031D01*
G01X249393D02*
X251293Y-193431D01*
G01X256993Y-190764D02*
X260193D01*
X259893Y-189831D01*
X259393Y-189297D01*
X258693Y-189031D01*
X257993Y-189164D01*
X257393Y-189564D01*
X256993Y-190497D01*
X256793Y-191298D01*
Y-192097D01*
X256993Y-192897D01*
X257493Y-193697D01*
X258093Y-194231D01*
X258793Y-194364D01*
X259493Y-194097D01*
X260193Y-193298D01*
G01X265093Y-194364D02*
Y-189031D01*
G01Y-190097D02*
X265593Y-189564D01*
X266093Y-189164D01*
X266793Y-189031D01*
X267293Y-189164D01*
X267893Y-189564D01*
G01X254793Y-236364D02*
X257193D01*
G01X255993D02*
Y-244364D01*
G01X254793D02*
X257193D01*
G01X262593D02*
Y-239031D01*
G01Y-240097D02*
X263093Y-239564D01*
X263593Y-239164D01*
X264293Y-239031D01*
X264793Y-239164D01*
X265393Y-239564D01*
G01X270493Y-240764D02*
X273693D01*
X273393Y-239831D01*
X272893Y-239297D01*
X272193Y-239031D01*
X271493Y-239164D01*
X270893Y-239564D01*
X270493Y-240497D01*
X270293Y-241298D01*
Y-242097D01*
X270493Y-242897D01*
X270993Y-243697D01*
X271593Y-244231D01*
X272293Y-244364D01*
X272993Y-244097D01*
X273693Y-243298D01*
G01X278293Y-244364D02*
Y-239031D01*
G01Y-240364D02*
X278693Y-239697D01*
X279293Y-239164D01*
X280093Y-239031D01*
X280793Y-239164D01*
X281393Y-239697D01*
X281693Y-240631D01*
Y-244364D01*
G01X286493Y-240764D02*
X289693D01*
X289393Y-239831D01*
X288893Y-239297D01*
X288193Y-239031D01*
X287493Y-239164D01*
X286893Y-239564D01*
X286493Y-240497D01*
X286293Y-241298D01*
Y-242097D01*
X286493Y-242897D01*
X286993Y-243697D01*
X287593Y-244231D01*
X288293Y-244364D01*
X288993Y-244097D01*
X289693Y-243298D01*
G01X260993Y-211364D02*
X263493Y-219364D01*
X265993Y-211364D01*
G01X273693Y-212031D02*
X273093Y-211631D01*
X272393Y-211364D01*
X271593D01*
X270693Y-211764D01*
X269993Y-212431D01*
X269493Y-213231D01*
X269093Y-214564D01*
X268993Y-215764D01*
X269193Y-216964D01*
X269493Y-217764D01*
X270093Y-218564D01*
X270793Y-219097D01*
X271493Y-219364D01*
X272193D01*
X272893Y-219097D01*
X273493Y-218697D01*
X273993Y-218164D01*
G01X281693Y-212031D02*
X281093Y-211631D01*
X280393Y-211364D01*
X279593D01*
X278693Y-211764D01*
X277993Y-212431D01*
X277493Y-213231D01*
X277093Y-214564D01*
X276993Y-215764D01*
X277193Y-216964D01*
X277493Y-217764D01*
X278093Y-218564D01*
X278793Y-219097D01*
X279493Y-219364D01*
X280193D01*
X280893Y-219097D01*
X281493Y-218697D01*
X281993Y-218164D01*
G01X287493Y-219364D02*
Y-211364D01*
X286293Y-212964D01*
G01Y-219364D02*
X288693D01*
G01X287193Y-194364D02*
Y-186364D01*
X283493Y-192097D01*
X288493D01*
G01X359093Y-237697D02*
X359693Y-236897D01*
X360393Y-236497D01*
X361193Y-236364D01*
X362193Y-236631D01*
X362893Y-237297D01*
X363093Y-238097D01*
X362993Y-238898D01*
X362593Y-239564D01*
X360593Y-240897D01*
X359693Y-241831D01*
X359093Y-243164D01*
X358893Y-244364D01*
X363093D01*
G01X368993Y-236364D02*
X368193Y-236631D01*
X367593Y-237297D01*
X367193Y-238097D01*
X366893Y-239164D01*
X366793Y-240364D01*
X366893Y-241564D01*
X367193Y-242631D01*
X367593Y-243431D01*
X368193Y-244097D01*
X368993Y-244364D01*
X369793Y-244097D01*
X370393Y-243431D01*
X370793Y-242631D01*
X371093Y-241564D01*
X371193Y-240364D01*
X371093Y-239164D01*
X370793Y-238097D01*
X370393Y-237297D01*
X369793Y-236631D01*
X368993Y-236364D01*
G01X376993Y-244364D02*
Y-236364D01*
X375793Y-237964D01*
G01Y-244364D02*
X378193D01*
G01X383093Y-237697D02*
X383693Y-236897D01*
X384393Y-236497D01*
X385193Y-236364D01*
X386193Y-236631D01*
X386893Y-237297D01*
X387093Y-238097D01*
X386993Y-238898D01*
X386593Y-239564D01*
X384593Y-240897D01*
X383693Y-241831D01*
X383093Y-243164D01*
X382893Y-244364D01*
X387093D01*
G01X391193Y-244631D02*
X394793Y-236364D01*
G01X400993Y-244364D02*
Y-236364D01*
X399793Y-237964D01*
G01Y-244364D02*
X402193D01*
G01X408993Y-236364D02*
X408193Y-236631D01*
X407593Y-237297D01*
X407193Y-238097D01*
X406893Y-239164D01*
X406793Y-240364D01*
X406893Y-241564D01*
X407193Y-242631D01*
X407593Y-243431D01*
X408193Y-244097D01*
X408993Y-244364D01*
X409793Y-244097D01*
X410393Y-243431D01*
X410793Y-242631D01*
X411093Y-241564D01*
X411193Y-240364D01*
X411093Y-239164D01*
X410793Y-238097D01*
X410393Y-237297D01*
X409793Y-236631D01*
X408993Y-236364D01*
G01X415193Y-244631D02*
X418793Y-236364D01*
G01X422793Y-242764D02*
X423393Y-243697D01*
X424193Y-244231D01*
X425093Y-244364D01*
X425893Y-244231D01*
X426693Y-243564D01*
X427193Y-242764D01*
X427293Y-241964D01*
X427093Y-241031D01*
X426393Y-240364D01*
X425693Y-240097D01*
X424793D01*
G01X425693D02*
X426293Y-239697D01*
X426793Y-239031D01*
X426993Y-238231D01*
X426793Y-237431D01*
X426293Y-236764D01*
X425393Y-236364D01*
X424493Y-236497D01*
X423593Y-237031D01*
G01X432993Y-244364D02*
Y-236364D01*
X431793Y-237964D01*
G01Y-244364D02*
X434193D01*
G01X358793Y-219364D02*
Y-211364D01*
X360793D01*
X361593Y-211764D01*
X362193Y-212297D01*
X362693Y-213097D01*
X363093Y-214031D01*
X363193Y-215364D01*
X363093Y-216697D01*
X362693Y-217631D01*
X362193Y-218431D01*
X361593Y-218964D01*
X360793Y-219364D01*
X358793D01*
G01X366493D02*
X368993Y-211364D01*
X371493Y-219364D01*
G01X370593Y-216564D02*
X367393D01*
G01X376993Y-211364D02*
Y-219364D01*
G01X374693Y-211364D02*
X379293D01*
G01X383093Y-216031D02*
X383793Y-215097D01*
X384393Y-214564D01*
X385193Y-214297D01*
X385893Y-214564D01*
X386393Y-215097D01*
X386793Y-215897D01*
X386893Y-216831D01*
X386793Y-217631D01*
X386393Y-218431D01*
X385793Y-219097D01*
X385093Y-219364D01*
X384293Y-219097D01*
X383593Y-218298D01*
X383193Y-217097D01*
X383093Y-215764D01*
X383293Y-214031D01*
X383593Y-213097D01*
X384093Y-212164D01*
X384793Y-211497D01*
X385493Y-211364D01*
X386193Y-211631D01*
X386693Y-212297D01*
G01X390393Y-219364D02*
Y-211364D01*
X392993Y-218031D01*
X395593Y-211364D01*
Y-219364D01*
G01X400993Y-211364D02*
Y-219364D01*
G01X398693Y-211364D02*
X403293D01*
G01X406893Y-219364D02*
Y-211364D01*
G01X411093D02*
Y-219364D01*
G01Y-215364D02*
X406893D01*
G01X414793Y-217764D02*
X415393Y-218697D01*
X416193Y-219231D01*
X417093Y-219364D01*
X417893Y-219231D01*
X418693Y-218564D01*
X419193Y-217764D01*
X419293Y-216964D01*
X419093Y-216031D01*
X418393Y-215364D01*
X417693Y-215097D01*
X416793D01*
G01X417693D02*
X418293Y-214697D01*
X418793Y-214031D01*
X418993Y-213231D01*
X418793Y-212431D01*
X418293Y-211764D01*
X417393Y-211364D01*
X416493Y-211497D01*
X415593Y-212031D01*
G01X422493Y-219364D02*
X424993Y-211364D01*
X427493Y-219364D01*
G01X426593Y-216564D02*
X423393D01*
G01X430793Y-219364D02*
Y-211364D01*
X432793D01*
X433593Y-211764D01*
X434193Y-212297D01*
X434693Y-213097D01*
X435093Y-214031D01*
X435193Y-215364D01*
X435093Y-216697D01*
X434693Y-217631D01*
X434193Y-218431D01*
X433593Y-218964D01*
X432793Y-219364D01*
X430793D01*
G01X440993Y-211364D02*
X440193Y-211631D01*
X439593Y-212297D01*
X439193Y-213097D01*
X438893Y-214164D01*
X438793Y-215364D01*
X438893Y-216564D01*
X439193Y-217631D01*
X439593Y-218431D01*
X440193Y-219097D01*
X440993Y-219364D01*
X441793Y-219097D01*
X442393Y-218431D01*
X442793Y-217631D01*
X443093Y-216564D01*
X443193Y-215364D01*
X443093Y-214164D01*
X442793Y-213097D01*
X442393Y-212297D01*
X441793Y-211631D01*
X440993Y-211364D01*
G01X380993Y-186364D02*
Y-194364D01*
G01X378693Y-186364D02*
X383293D01*
G01X387093Y-191031D02*
X387793Y-190097D01*
X388393Y-189564D01*
X389193Y-189297D01*
X389893Y-189564D01*
X390393Y-190097D01*
X390793Y-190897D01*
X390893Y-191831D01*
X390793Y-192631D01*
X390393Y-193431D01*
X389793Y-194097D01*
X389093Y-194364D01*
X388293Y-194097D01*
X387593Y-193298D01*
X387193Y-192097D01*
X387093Y-190764D01*
X387293Y-189031D01*
X387593Y-188097D01*
X388093Y-187164D01*
X388793Y-186497D01*
X389493Y-186364D01*
X390193Y-186631D01*
X390693Y-187297D01*
G01X394393Y-194364D02*
Y-186364D01*
X396993Y-193031D01*
X399593Y-186364D01*
Y-194364D01*
G01X401993Y-197031D02*
X407993D01*
G01X415193Y-187031D02*
X414593Y-186631D01*
X413893Y-186364D01*
X413093D01*
X412193Y-186764D01*
X411493Y-187431D01*
X410993Y-188231D01*
X410593Y-189564D01*
X410493Y-190764D01*
X410693Y-191964D01*
X410993Y-192764D01*
X411593Y-193564D01*
X412293Y-194097D01*
X412993Y-194364D01*
X413693D01*
X414393Y-194097D01*
X414993Y-193697D01*
X415493Y-193164D01*
G01X418393Y-194364D02*
Y-186364D01*
X420993Y-193031D01*
X423593Y-186364D01*
Y-194364D01*
G01X425993Y-197031D02*
X431993D01*
G01X434793Y-194364D02*
Y-186364D01*
X436793D01*
X437593Y-186764D01*
X438193Y-187297D01*
X438693Y-188097D01*
X439093Y-189031D01*
X439193Y-190364D01*
X439093Y-191697D01*
X438693Y-192631D01*
X438193Y-193431D01*
X437593Y-193964D01*
X436793Y-194364D01*
X434793D01*
G01X473793Y-244364D02*
Y-236364D01*
X475793D01*
X476593Y-236764D01*
X477193Y-237297D01*
X477693Y-238097D01*
X478093Y-239031D01*
X478193Y-240364D01*
X478093Y-241697D01*
X477693Y-242631D01*
X477193Y-243431D01*
X476593Y-243964D01*
X475793Y-244364D01*
X473793D01*
G01X503493D02*
Y-236364D01*
X502293Y-237964D01*
G01Y-244364D02*
X504693D01*
G01X509593Y-241031D02*
X510293Y-240097D01*
X510893Y-239564D01*
X511693Y-239297D01*
X512393Y-239564D01*
X512893Y-240097D01*
X513293Y-240897D01*
X513393Y-241831D01*
X513293Y-242631D01*
X512893Y-243431D01*
X512293Y-244097D01*
X511593Y-244364D01*
X510793Y-244097D01*
X510093Y-243298D01*
X509693Y-242097D01*
X509593Y-240764D01*
X509793Y-239031D01*
X510093Y-238097D01*
X510593Y-237164D01*
X511293Y-236497D01*
X511993Y-236364D01*
X512693Y-236631D01*
X513193Y-237297D01*
M02*
